M48
INCH,TZ
T01C.001
T02C.01
T03C.012
T04C.014
T05C.01417
T06C.016
T07C.02
T08C.028
T09C.02834
T10C.02913
T11C.119
T12C.138
T13C.14
T14C.166
T15C.168
T16C.225
T17C.037
T18C.053
T19C.086
T20C.087
T21C.093
T22C.094
T23C.097
T24C.111
T25C.404
;LEADER: 12 
;HEADER: 
;CODE  : ASCII 
;FILE  : 16315-1-1-12.drl for board 16315-1.brd ... layers TOP and BOTTOM
;T01 Holesize 1. = 1.000000 Tolerance = +0.000000/-0.000000 PLATED MILS Quantity = 26
;T02 Holesize 2. = 10.000000 Tolerance = +0.000000/-0.000000 PLATED MILS Quantity = 288
;T03 Holesize 3. = 12.000000 Tolerance = +0.000000/-0.000000 PLATED MILS Quantity = 4233
;T04 Holesize 4. = 14.000000 Tolerance = +0.000000/-0.000000 PLATED MILS Quantity = 35
;T05 Holesize 5. = 14.170000 Tolerance = +0.000000/-0.000000 PLATED MILS Quantity = 968
;T06 Holesize 6. = 16.000000 Tolerance = +0.000000/-0.000000 PLATED MILS Quantity = 1567
;T07 Holesize 7. = 20.000000 Tolerance = +0.000000/-0.000000 PLATED MILS Quantity = 91
;T08 Holesize 8. = 28.000000 Tolerance = +0.000000/-0.000000 PLATED MILS Quantity = 60
;T09 Holesize 9. = 28.340000 Tolerance = +0.000000/-0.000000 PLATED MILS Quantity = 656
;T10 Holesize 10. = 29.130000 Tolerance = +0.000000/-0.000000 PLATED MILS Quantity = 62
;T11 Holesize 11. = 119.000000 Tolerance = +0.000000/-0.000000 PLATED MILS Quantity = 1
;T12 Holesize 12. = 138.000000 Tolerance = +0.000000/-0.000000 PLATED MILS Quantity = 1
;T13 Holesize 13. = 140.000000 Tolerance = +0.000000/-0.000000 PLATED MILS Quantity = 6
;T14 Holesize 14. = 166.000000 Tolerance = +0.000000/-0.000000 PLATED MILS Quantity = 3
;T15 Holesize 15. = 168.000000 Tolerance = +0.000000/-0.000000 PLATED MILS Quantity = 8
;T16 Holesize 16. = 225.000000 Tolerance = +0.000000/-0.000000 PLATED MILS Quantity = 4
;T17 Holesize 17. = 37.000000 Tolerance = +0.000000/-0.000000 NON_PLATED MILS Quantity = 37
;T18 Holesize 18. = 53.000000 Tolerance = +0.000000/-0.000000 NON_PLATED MILS Quantity = 37
;T19 Holesize 19. = 86.000000 Tolerance = +0.000000/-0.000000 NON_PLATED MILS Quantity = 7
;T20 Holesize 20. = 87.000000 Tolerance = +0.000000/-0.000000 NON_PLATED MILS Quantity = 8
;T21 Holesize 21. = 93.000000 Tolerance = +0.000000/-0.000000 NON_PLATED MILS Quantity = 8
;T22 Holesize 22. = 94.000000 Tolerance = +0.000000/-0.000000 NON_PLATED MILS Quantity = 2
;T23 Holesize 23. = 97.000000 Tolerance = +0.000000/-0.000000 NON_PLATED MILS Quantity = 2
;T24 Holesize 24. = 111.000000 Tolerance = +0.000000/-0.000000 NON_PLATED MILS Quantity = 4
;T25 Holesize 25. = 404.000000 Tolerance = +0.000000/-0.000000 NON_PLATED MILS Quantity = 2
%
G90
T01
X944882Y-70078
X796457Y251203
X131201Y365354
X379232
X627263
X1301870
X1549901
X1797933
X1181890Y544117
X796457Y723644
X131200Y818110
X379232
X627263
X1301870
X1549901
X1797933
X1181870Y957480
X961418Y1075613
X1797933Y1270866
X1549901
X1301870
X627263
X379232
X131201
X961418Y1418132
X1181890Y1548054
T02
X127988Y185742
Y190242
Y194242
Y181742
X252200Y190242
Y194242
Y185742
Y181742
X376413
Y185742
Y190242
Y194242
X500625Y190242
Y194242
Y181742
Y185742
X624838Y194242
Y181742
Y185742
Y190242
X749051Y185742
Y190242
Y181742
Y194242
X1252750Y167823
X1256750
X1261250
X1265250
X1266400Y182823
X1270400
X1274900
X1278900
X1376963Y167823
X1380963
X1385463
X1389463
X1402713Y190242
Y185742
Y181742
Y194242
X1502950Y181700
X1506950
X1511450
X1515450
X1526925Y185742
Y181742
Y190242
Y194242
X1632438Y175242
Y166742
Y170742
Y179242
X1651138Y194242
Y181742
Y190242
Y185742
X1756650Y175242
Y170742
Y179242
Y166742
X1775350Y185742
Y190242
Y194242
Y181742
X1880863Y175242
Y170742
Y179242
Y166742
X1899563Y194242
Y190242
Y185742
Y181742
Y642998
Y634498
Y646998
Y638498
X1880863Y631998
Y627998
Y623498
Y619498
X1731650
Y631998
Y627998
Y623498
X1725350Y646998
Y642998
Y638498
Y634498
X1651138Y646998
Y642998
Y638498
Y634498
X1632438Y623498
Y631998
Y619498
Y627998
X1526925Y634498
Y646998
Y642998
Y638498
X1508225Y631998
Y627998
Y623498
Y619498
X1402713Y646998
Y638498
Y642998
Y634498
X1384013Y631998
Y619498
Y627998
Y623498
X1278500Y646998
Y642998
Y638498
Y634498
X1259800Y627998
Y631998
Y623498
Y619498
X749051Y646998
Y634498
Y638498
Y642998
X624838Y646998
Y634498
Y638498
Y642998
X500625Y638498
Y634498
Y642998
Y646998
X376413Y634498
Y646998
Y642998
Y638498
X252200Y642998
Y638498
Y634498
Y646998
X127988
Y634498
Y642998
Y638498
Y1099754
Y1087254
Y1091254
Y1095754
X252200Y1087254
Y1099754
Y1095754
Y1091254
X376413Y1095754
Y1091254
Y1087254
Y1099754
X500625Y1091254
Y1087254
Y1095754
Y1099754
X624838Y1095754
Y1091254
Y1099754
Y1087254
X749051Y1099754
Y1091254
Y1087254
Y1095754
X1259800Y1076254
Y1080754
Y1072254
Y1084754
X1278500Y1091254
Y1087254
Y1095754
Y1099754
X1384013Y1076254
Y1080754
Y1084754
Y1072254
X1402713Y1095754
Y1091254
Y1087254
Y1099754
X1508225Y1080754
Y1084754
Y1076254
Y1072254
X1526925Y1087254
Y1095754
Y1099754
Y1091254
X1632438Y1084754
Y1076254
Y1080754
Y1072254
X1651138Y1091254
Y1087254
Y1099754
Y1095754
X1756650Y1084754
Y1072254
Y1076254
Y1080754
X1775350Y1099754
Y1091254
Y1087254
Y1095754
X1880863Y1080754
Y1076254
Y1072254
Y1084754
X1899563Y1087254
Y1095754
Y1091254
Y1099754
X1079250Y1238209
Y1231122
Y1224035
Y1245295
Y1216949
Y1209862
X1075250Y1245295
Y1216949
Y1224035
Y1209862
Y1238209
Y1231122
X1070750
Y1209862
Y1245295
Y1224035
Y1238209
Y1216949
X1066750Y1231122
Y1209862
Y1224035
Y1216949
Y1245295
Y1238209
Y1294902
X1070750
X1075250
X1079250
Y1301988
Y1330335
Y1323248
Y1316161
Y1309075
X1075250Y1301988
Y1323248
Y1330335
Y1316161
Y1309075
X1070750Y1323248
Y1330335
Y1309075
Y1301988
Y1316161
X1066750Y1323248
Y1301988
Y1309075
Y1330335
Y1316161
X1079250Y1379941
Y1387028
Y1394114
X1075250Y1387028
Y1394114
Y1379941
X1070750
Y1387028
Y1394114
X1066750
Y1379941
Y1387028
Y1408287
Y1401201
Y1415374
X1070750Y1401201
Y1408287
Y1415374
X1075250Y1401201
Y1415374
Y1408287
X1079250Y1415374
Y1401201
Y1408287
T03
X40000Y40000
Y60000
X20000
Y80000
X40000
Y100000
X20000
Y120000
X40000
Y140000
X20000
X40000Y160000
X20000
Y180000
Y200000
X38500Y202000
X49937Y219661
X20000Y220000
Y240000
X49437Y254661
X20000Y260000
X40000Y280000
X20000
X40000Y300000
X20000
Y320000
X40000
Y340000
X20000
X40000Y360000
X20000
Y380000
Y400000
Y420000
Y440000
X35000Y446500
X39853Y512373
X44111Y516510
X47607Y527511
X40000Y560000
Y580000
Y600000
Y620000
X39000Y646000
X27143Y663071
X30676Y663764
X49937Y672417
X30697Y679553
X27510Y688422
X31043Y689115
X31064Y704904
X49437Y707417
X49500Y729000
X38500Y800500
X49000Y811000
X39000Y834500
X15000Y920000
X25000
X40000
Y930000
X25000
X15000
X40000Y940000
X15000
X25000
X40000Y950000
X25000
X15000
X40000Y960000
X25000
X15000
X40000Y970000
X25000
X15000
Y980000
X25000
Y990000
X15000
X40000
X15000Y1000000
X25000
X40000
X25000Y1010000
X15000
X25000Y1020000
X15000
Y1030000
X25000Y1040000
Y1050000
Y1060000
Y1070000
Y1080000
Y1090000
X47000Y1107500
X26723Y1116038
X30256Y1116731
X49937Y1125173
X39325Y1131400
X30670Y1132472
X27090Y1141389
X30623Y1142082
X30644Y1157871
X49437Y1160173
X36848Y1173600
X19712Y1176350
X25000Y1190400
X30000
X31500Y1224000
X39425Y1226200
X37225Y1230100
X17500Y1240000
Y1250000
Y1260000
Y1270000
Y1280000
Y1290000
Y1300000
X45800Y1306100
X17500Y1310000
Y1320000
Y1330000
X41381Y1335567
X45518Y1336366
X17500Y1340000
Y1350000
X37500Y1360000
X27500
X17500
X93000Y1319000
X86000Y1282000
X90000Y1252500
X98500Y1241000
X95437Y1205673
X71500Y1205000
X52000Y1186000
X89237Y1182373
X73437Y1152673
Y1140173
X54437Y1125173
X58937
X81000Y1124500
X64487Y1118173
X88937Y1107173
X83937
X73937
X64487
X78937
X86637Y1100373
X92287Y1100173
X74937Y1092973
X95537Y1086673
X53027Y1085073
X95537Y1082173
X74000Y1074000
X50000Y1060000
X85000
X50000Y1030000
X70000Y1020000
X85000
X99700Y991400
X58175Y981325
X98563Y977225
X97063Y973225
X72500Y961355
X67500
X90000Y858000
X51000Y846000
X89500Y802500
X94000Y789000
X69500Y777000
X75500Y757500
X51000Y755500
X95437Y752917
X89237Y729617
X73437Y699917
Y687417
X58937Y672417
X54437
X81500Y672000
X64487Y665417
X78937Y654417
X73937
X83937
X64487
X88937
X86637Y647617
X92287Y647417
X74937Y640217
X95437Y633917
X53087Y632317
X85146Y621637
X88000Y602500
Y577500
X89000Y557500
X50500Y545500
X87000Y541000
X61834Y527515
X86500Y522000
X58346Y516473
X54088Y512336
X67500Y508600
X72500
X89000Y403500
X60000Y340000
X80000
X96000Y336500
X80000Y320000
X60000
X95437Y300161
X60000Y300000
X89237Y276861
X62000Y276500
X73437Y247161
X56000Y237000
X73437Y234661
X58937Y219661
X54437
X82000Y219000
X64487Y212761
Y201761
X78937Y201661
X88937
X73937
X83937
X86637Y194861
X92287Y194661
X74937Y187461
X95437Y181161
X53087Y179561
X95437Y176661
X78500Y169500
X60000Y160000
X86500Y157500
X60000Y140000
X80000
X60000Y120000
X80000
X60000Y100000
X80000
X60000Y80000
X80000
X60000Y60000
Y40000
Y20000
X140000Y40000
Y60000
X120000Y80000
X140000
X100000
Y100000
X140000
X120000
X140000Y120000
X120000
X100000
X140000Y140000
X118437Y141870
X111437Y165492
Y180492
Y195492
X106937Y198543
Y207992
X130500Y211500
X106937Y217441
X111437Y235492
X142687Y237161
X111437Y245492
X142687Y248100
X129000Y259000
X111437Y265492
X145437Y265561
X111437Y275492
X128000Y288500
X140000Y300000
X118437Y314114
X140000Y320000
X100000Y420000
X140000Y440000
X120000
X100000
X120000Y460000
X100000
X140000
Y480000
X100000
X120000
Y500000
X100000
X140000
X142500Y515500
X104500
X120500Y524000
X100000Y541500
X146263Y568725
X138763
X108500Y572000
X144263Y573225
X148763Y576225
X135000Y588000
X118753Y594626
X147500Y605500
X111437Y618248
Y633248
Y648248
X106937Y651299
Y660748
Y670197
X111437Y688248
X142687Y689917
X111437Y698248
X142687Y700767
X145437Y717617
X111437Y718248
Y728248
X140372Y732370
X135200Y738400
X140364Y749807
X118437Y766870
X100000Y880000
Y900000
X120000
X100000Y920000
X120000
X140000
Y940000
X120000
X100000
X119163Y959625
X115800Y971200
X119800
Y975200
X115800
Y979200
X119800
X101403Y981195
X119800Y983200
X111800
X115800
X130463Y983925
X137163Y987125
X119800Y987200
X115800
X111800
X108063Y991925
X104230Y992209
X114300Y992362
X131110Y993257
X137063Y993725
X145363Y997741
X114100Y1002600
X121914Y1003491
X133063Y1012725
X120000Y1025000
X118437Y1047382
X134000Y1064000
X111437Y1071004
Y1086004
X148400Y1086900
X111437Y1101004
X106937Y1104055
Y1113504
X132000Y1117000
X106937Y1122953
X111437Y1141004
X142687Y1142673
X111437Y1151004
X142687Y1153523
X145437Y1165673
X111437Y1171004
Y1181004
X148311Y1182767
X140422Y1190937
X135422
X118437Y1219626
X148300Y1228800
X163500Y1345200
X190000Y1320000
Y1310000
X181000Y1261000
X153824Y1197248
X170000Y1190500
X153932Y1182940
X153716Y1174793
X154363Y1161725
X173649Y1160173
X197649Y1152673
X150862Y1152723
X175000Y1143000
X193423Y1140945
X178649Y1125173
X183149
X174149
X188399Y1113873
X198149Y1107173
X153000Y1105000
X188399Y1102873
X195100Y1096800
X177105Y1094839
X199149Y1092973
X156000Y1032000
X194052Y1019166
X188552
X184295Y1014969
X198741Y1014882
X184295Y1009469
X198741Y1009382
X184017Y951112
X198463Y951025
X184017Y945612
X198463Y945525
X188706Y941328
X194206
X160000Y940000
X199900Y923200
X160000Y920000
X180000
X160000Y900000
X180000
Y880000
X160000
X180000Y860000
X153705Y744831
X153714Y720741
X153757Y710653
X150253Y709713
X173649Y707417
X197649Y699917
Y687417
X182259Y672559
X173259
X177759
X198149Y654417
X199149Y631217
X185149Y617949
X167000Y613000
X199763Y600725
X188614Y591491
X180800Y590600
X197810Y581257
X181000Y580362
X170930Y580209
X174763Y579925
X166400Y579400
X178500Y575200
X186500
X182500
X197163Y571925
X182500Y571200
X186500
X178500
X168103Y569195
X153263Y568725
X182500Y567200
X186500
X165263Y565225
X182500Y563200
X186500
X163763Y561225
X186500Y559200
X182500
X186088Y527473
X171861Y527469
X150000Y526500
X168365Y516368
X182600Y516331
X178342Y512294
X164107Y512331
X191712Y508600
X196712
X180000Y340000
X160000Y320000
X180000
X160000Y300000
X180000
X160000Y280000
X173649Y254661
X197649Y247161
X180500Y237000
X197649Y234661
X178649Y219661
X183149
X174149
X188699Y212561
X198149Y201661
X188699Y200561
X160500Y190000
X199149Y187461
X160000Y180000
X177399Y179661
X156500Y170500
X160000Y140000
X180000
Y120000
X160000
X180000Y100000
X160000
Y80000
X180000
Y60000
X160000
Y40000
X180000
Y20000
X160000
X220000
X240000
X200000
X220000Y40000
X240000
X200000
X220000Y60000
X240000
X200000
X240000Y80000
X200000
X220000
Y100000
X200000
X240000
X200000Y120000
X240000
X220000
X200000Y140000
X242649Y141870
X235649Y165492
X219749Y176661
X235649Y180492
X219749Y181361
X216500Y194756
X210849Y194861
X235649Y195492
X231991Y198543
X208149Y201661
X213149
X203149
X231149Y207992
Y217441
X206000Y219000
X235649Y235492
Y245492
Y265492
Y275492
X213449Y276861
X219649Y300161
X242649Y314114
X200000Y340000
X220000Y360000
Y380000
X240000
Y400000
X220000
Y420000
X240000
Y440000
X220000
X240000Y460000
X220000
X240000Y480000
X220000
X240000Y500000
X220000
Y520000
X210263Y546725
X203863Y575125
X203763Y581725
X212063Y585741
X243051Y594626
X207313Y598113
X235649Y618248
X219749Y618917
Y623417
X235649Y633248
X216499Y636917
X210849Y638617
X210000Y644000
X235649Y648248
X210000Y650000
X231149Y651299
X208149Y654417
X203149
X213149
X231149Y660748
Y670197
X206000Y672000
X235649Y688248
Y698248
Y718248
Y728248
X213449Y729617
X219649Y752917
X242649Y766870
X248500Y788500
X225000Y815000
Y840000
X245000
Y860000
X225000
X245000Y880000
X225000
Y900000
X245000
X223100Y920600
X245000Y940000
X216712Y961155
X221712
X239000Y985600
X227063Y994925
X211563Y1001225
X203563
X215563
X223563
X207563
X219563
X244600Y1004600
X242649Y1047382
X211000Y1065000
X235649Y1071004
X219749Y1082173
X235649Y1086004
X219749Y1086873
X216499Y1100173
X210849Y1100373
X235649Y1101004
X231149Y1104055
X203149Y1107173
X213149
X208149
X231149Y1113504
Y1122953
X203500Y1124500
X235300Y1142700
X235649Y1151004
Y1171004
Y1181004
X213449Y1182373
X219649Y1205673
X242649Y1219626
X220000Y1270000
X230000Y1280000
X220000
Y1290000
X240000
X230000
X220000Y1300000
X210000
X230000
X240000
X230000Y1310000
X220000
X240000
X200000
X210000
X240000Y1320000
X230000
X220000
X200000
X210000
X286100Y1349659
X289510Y1342259
X295900Y1339700
X292600Y1337367
X296100Y1335100
X283700Y1328300
X279900
X250000Y1320000
X260000
X250000Y1310000
X260000
X250000Y1300000
X260000
X250000Y1290000
X257000Y1253000
X276100Y1229100
X255000Y1207500
X286925Y1201945
X278076Y1197355
X264594Y1190768
X259594
X273243Y1182915
X278146Y1182940
X277930Y1175001
X269649Y1165673
X278577Y1161725
X275385Y1152596
X271165Y1147172
X266899Y1141173
X298362Y1125173
X264864Y1120500
X281000Y1105000
X295200Y1078400
X271100Y1063200
X295200Y1058400
X263000Y1047000
X281500Y1036744
X281200Y1033000
X263000Y1023000
X280800Y1011900
X261100Y1005700
X252100Y990100
X268100Y982300
X273300Y981700
X286000Y810500
X265000Y795000
X264731Y749551
X277972Y744575
X264739Y732114
X277981Y720485
X258600Y715500
X278024Y710397
X274520Y709457
X297862Y707417
X266899Y700767
Y689917
X298362Y672417
X255500Y664500
X275000Y647000
X277000Y618500
X255410Y607833
X260910
X294500Y607500
X284000
X250974Y602808
X265275Y602396
X250974Y597308
X265275Y596896
X286263Y589225
X282263
X278263
X290263
X274263
X270263
X293763Y582925
X250586Y539420
X265392Y539225
X250586Y533920
X265392Y533725
X260703Y529168
X255203
X296032Y527469
X292536Y516368
X288278Y512331
X292153Y486059
X295000Y460000
Y440000
X291601Y418503
X295000Y400000
X255000Y280000
X269649Y266261
X253000Y260000
X297862Y254661
X266899Y248011
Y237161
X298362Y219661
X262000Y209000
X285500Y189500
X283000Y181000
X270000Y179500
X260000Y140000
X280000
X260000Y120000
X280000
X260000Y100000
X280000
Y80000
X260000
X280000Y60000
X260000
X280000Y40000
X260000
X280000Y20000
X260000
X320000
X300000
X340000
Y40000
X300000
X320000
X334845Y58745
X346245
X322500Y68345
X303029Y68429
X312079Y68379
X322545Y72845
X312355Y72855
X303000Y73500
X344304Y82439
X339914Y82415
X334947Y94605
X339219Y95188
X347647Y95614
X313312Y98705
X317812Y98905
X345321Y102400
X335081Y104081
X313628Y112926
X347881Y114881
X337641Y114910
X342761Y114861
X323813Y118512
X314370Y118452
X345321Y118921
X341114Y123622
X333021Y129679
X337721Y129821
X323813Y133722
X314439Y133669
X328000Y150500
X344062Y176461
X301612Y179661
X343962Y181161
X323362Y187461
X340712Y194661
X335062Y194861
X312912Y201661
X332362
X327362
X322362
X337362
X314329Y212420
X333500Y219000
X302862Y219661
X307362
X321862Y234661
X304500Y237000
X321862Y247161
X337662Y276861
X300000Y300000
X343862Y300161
X300000Y320000
Y340000
X320000
X316534Y363234
X320474
Y379474
X316534
X330000Y440000
Y460000
X320925Y485385
X315925
X306388Y486022
X320925Y508600
X315925
X302513Y512294
X306771Y516331
X310259Y527473
X330000Y540000
X333000Y560000
Y580000
Y604000
X333682Y621858
X301612Y632417
X343862Y633917
X323362Y640217
X340712Y647517
X335062Y647617
X337362Y654417
X327362
X332362
X312912
X322362
X312912Y665417
X330000Y672000
X302862Y672417
X307362
X321862Y687417
Y699917
X337662Y729617
X320000Y750000
X343862Y752917
X330000Y770000
X347000Y788500
X316534Y832229
X320474
X330000Y900000
X335300Y926900
X315600Y933600
X320925Y938140
X330000Y960000
X315925Y961355
X320925
X337100Y972100
X322000Y988500
X344737Y995637
X328000Y1061000
X305200Y1068400
X344062Y1082073
X301327Y1085173
X344062Y1086773
X323362Y1092973
X340812Y1100273
X335062Y1100373
X313232Y1106499
X322362Y1107173
X332362
X327362
X337362
X312912Y1118273
X307362Y1125173
X302862
X321862Y1140173
X304500Y1142500
X321862Y1152673
X302452Y1165162
X331679Y1175800
X337662Y1182373
X306000Y1182500
X327500Y1197000
X343862Y1205673
X315500Y1216700
X301000Y1231000
X330000Y1302000
X398527Y1233336
X353000Y1231000
X366862Y1219626
X388849Y1191148
X383849Y1190833
X398527Y1188659
X359862Y1181004
X358518Y1171114
X383191Y1170203
X399474Y1166787
X385210Y1166347
X393679Y1157480
X391112Y1153500
X359862Y1151004
X391112Y1142673
X359862Y1141004
X355362Y1122953
X388888Y1118173
X355362Y1113504
Y1104055
X359862Y1101004
Y1086004
Y1071004
X390000Y1055000
X366862Y1047382
X350673Y1031200
X362000Y1017000
X393500
Y988500
X380000Y960000
X360000
Y940000
X380000
X397000Y911000
X361500Y901500
X355000Y780500
X366862Y766870
X398254Y763517
X388788Y749479
X388796Y732042
X359862Y728248
X393862Y719917
X359862Y718248
X398677Y709385
X391112Y700767
X359862Y698248
X391112Y689917
X359862Y688248
X355362Y670197
X379000Y664000
X355362Y660748
Y651299
X359862Y648248
Y633248
X395000Y631000
X359862Y618248
X388000Y607000
X366862Y594626
X389000Y594500
X350000Y560000
X390000
X370000
Y540000
X350000
X390000
X370000Y520000
X350000
X390000
Y500000
X350000
X370000
X350000Y480000
Y460000
Y440000
X352000Y331000
X366862Y314114
X385500Y313000
X389000Y289000
X359862Y275492
Y265492
X386800Y263800
X390412Y248011
X359862Y245492
X390312Y237161
X359862Y235492
X355362Y217441
X386000Y209000
X355362Y207992
Y198543
X359862Y195492
Y180492
Y165492
X395500Y160500
X388500Y153500
X366862Y141870
X350441Y117541
X353001Y114815
X377944Y95929
X351416Y95788
X365162Y88731
X377144Y84720
X353001Y81799
X365162Y77731
X361776Y70842
X351000Y70700
X354100Y62100
X380000Y60000
X355200Y58400
X360000Y40000
X380000
Y20000
X360000
X400000Y80000
X401000Y89000
X429224Y176300
X447574Y187461
X437124Y201661
Y212661
X446951Y213656
X427074Y219661
X431574
X422574
X446074Y234661
Y247161
X422300Y254661
X441645Y284647
Y288847
X440747Y363234
X444687
Y379474
X440747
X418600Y445462
X421700Y450200
X447533Y475900
X430538Y485985
X416303Y486022
X440138Y487743
X445138
Y508600
X440138
X412428Y512294
X426663Y512257
X430921Y516294
X416686Y516331
X434409Y527436
X420182Y527432
X430000Y545500
X440000Y560000
X445000Y600000
X440000Y613000
X425824Y632317
X447574Y640217
X417000Y652500
X446574Y654417
X437224
Y665417
X431574Y672417
X422574
X427074
X446074Y687417
X410000Y692500
X446074Y699917
X422074Y707417
X402181Y710325
X402138Y720413
X437500Y744000
X402129Y744503
X440000Y760000
X407714Y761291
X445000Y780000
X402500Y780500
X445000Y798000
X444687Y816765
X440747
Y832229
X444687
X435082Y915200
X437600Y917800
X445582Y925352
X445138Y938140
X440138
X445138Y961355
X440138
X449137Y967757
X428000Y988500
X442600Y998300
X408672Y1008038
X432657Y1015102
X429613Y1017920
X413000Y1054200
X447173Y1068726
X442473
X424000Y1105000
X441976Y1107576
X446627Y1112973
X447919Y1121725
X437104Y1160696
X441400Y1169400
X418500Y1176800
X402403Y1188312
X406037Y1192706
X424000Y1206000
X416900Y1221800
X440000Y1320000
X412300Y1326200
X415422Y1352000
X418922Y1356522
X422373Y1359747
X480000Y1320000
X460000
X480000Y1300000
X460000
X480000Y1280000
X454500Y1248500
X476373Y1219498
X450500Y1208500
X468074Y1205673
X461874Y1182373
X484074Y1181004
Y1171004
Y1151004
Y1141004
X465346Y1122953
X452419Y1121725
X456919
X479574Y1113504
Y1104055
X484074Y1101004
X453473Y1089300
X484074Y1086004
X460873Y1077526
X460673Y1071976
X484074Y1071004
X491074Y1047382
X468000Y1047000
X465200Y1018200
X462000Y988500
X480000Y960000
Y940000
X455000Y780000
X461500Y769500
X491074Y766870
X468074Y752917
X452500Y744500
X461874Y729617
X484074Y728248
Y718248
Y698248
Y688248
X454500Y672000
X479574Y670197
Y660748
X461574Y654417
X456574
X451574
X479574Y651299
X484074Y648248
X459274Y647617
X464924Y647417
X468174Y633917
X484074Y633248
X457853Y622091
X484074Y618248
X460000Y600000
X491074Y594626
X472022Y582062
X460000Y560000
X499000Y553000
X460000Y540000
X497351Y531531
X465000Y491000
X481533Y480875
X462133Y473300
X458679Y470700
X450500Y459562
X470000Y430000
X452800Y420912
X470000Y400000
Y380000
X456190Y354105
X491074Y314114
X468074Y300161
X461874Y276861
X484074Y275492
X481174Y265492
X484074Y245492
Y235492
X478651Y220734
X456951Y213656
X461951
X451951
X480159Y201245
X478306Y195593
X461122Y194861
X468472Y182441
X497785Y178034
X462200Y173109
X476319Y144481
X509180Y145419
X506750Y165324
X539584Y184694
X542155Y187543
X546009Y187821
X500184Y200328
X519868Y242334
X515324Y252511
X510700Y277200
X515500Y301000
X515000Y322500
X548500Y343000
X534905Y354105
X547500Y440000
X524856Y486022
X510621Y486059
X539350Y487659
X534350
Y508600
X539350
X520981Y512294
X506746Y512331
X549279Y513331
X525239Y516331
X511004Y516368
X514500Y524469
X528727Y524973
X501023Y534941
X525579Y538331
X530130Y547167
X518700Y548700
X520579Y553231
X548767Y556819
X533879Y566031
X527179Y568731
X517499Y576931
X540000Y583000
Y600000
X520000
X528000Y611000
X532000Y623000
X549937Y632317
X546787Y672417
X515324Y689917
Y700667
X546287Y707417
X522773Y709638
X526277Y710578
X509996Y716996
X526234Y720666
X512892Y732295
X526225Y744756
X512884Y749732
X509000Y772000
X523500Y883500
X525000Y937000
X500000Y940000
Y960000
X525500Y967000
X504000Y988500
X515800Y1028000
X530800Y1028300
X523000Y1045000
X506500Y1051900
X528500Y1073500
X549773Y1085173
X524474Y1107073
X529474
X519474
X504724
X514474
X504724Y1118073
X546787Y1125173
X505874Y1134773
X509037Y1136700
X534874Y1139774
X506700Y1141973
Y1145973
X535320Y1152771
X524828Y1159231
X546287Y1160173
X526501Y1166546
X526523Y1177122
X526367Y1183111
X522867Y1190284
X508103Y1190557
X513103
X526388Y1197747
X502500Y1211500
X522867Y1231097
X500000Y1300000
X539000Y1309000
X520600Y1324100
X527000Y1340600
X521500Y1342800
X512900Y1345600
X541362Y1359826
X536000
X518397Y1360000
X553587Y1346026
X590000Y1247000
X592400Y1214456
X592287Y1205673
X567500Y1189500
X586087Y1182373
X570287Y1152673
Y1140173
X555787Y1125173
X551287
X561337Y1120873
Y1107173
X575787
X580787
X585787
X570787
X583487Y1100373
X589137Y1100173
X571787Y1092973
X592387Y1086873
Y1082173
X586500Y1061500
X575000Y1057500
X586000Y1046500
X575000Y1046000
X556022Y1042817
X552436Y1042494
X571400Y1000100
X571000Y988000
X589500
X564350Y961355
X569350
Y941640
X564350
X592000Y900500
X551500Y888000
X592614Y882300
X593365Y877358
X555500Y852000
X568899Y832229
X564959
X592287Y752917
X559000Y741000
X586087Y729617
X570287Y699917
Y687417
X555787Y672417
X551287
X579000Y672000
X561437Y665417
X570787Y654417
X585787
X575787
X580787
X561437
X583487Y647617
X589137Y647417
X571787Y640217
X592387Y634017
Y629417
X586000Y611000
X580000Y600000
X560000
X592000Y595000
X567641Y577473
X584279Y577431
X592779
X571408Y577450
X575779Y577431
X579718
X588779
X562279
X557279Y570331
X579529Y562951
X571529
X585479Y543994
X570779Y542831
X585479Y537731
X575700Y528831
X553279Y523331
X572229Y520081
X593079Y516531
X557279Y513331
X553279
X575779Y512831
X568779
X580279
X593079Y512531
X563279Y506731
X569529Y502127
X594500Y462000
X560000Y438500
X568899Y379474
X564959
X568899Y363234
X564959
X590000Y342000
X592287Y300161
X582758Y276861
X553742Y267705
X550987Y262810
X569009Y247887
X570287Y234661
X557057Y220152
X550219Y220111
X553674Y220121
X563000Y217600
X588188Y216520
X572697Y200744
X587697
X582697
X577697
X561437Y197249
X586719Y196888
X583487Y194861
X568687Y187660
X598236Y181981
X592767Y179277
X566271Y167387
X613500Y66000
X634500Y77000
X629024Y107633
X607929Y112329
X619171
X614967Y134777
X606718Y168580
X603697Y182091
X604517Y196263
X603787Y207992
X608287Y235492
X639537Y237161
X608287Y245492
X639537Y248011
X607961Y263934
X642287Y266461
X608287Y275492
X649500Y285000
X615287Y314114
X649000Y429500
X612000Y502300
X647663Y502400
X638263Y503494
X624028Y503558
X620153Y511994
X634388Y511957
X615100Y513287
X638646Y515994
X624411Y516031
X647663Y516600
X642509Y520667
X627863Y522000
X609334Y538306
X627000Y538581
Y542909
X609334Y543306
X619560Y547201
X602379Y547831
X643000Y549500
X615119Y551586
X602779Y552331
X623236Y562574
X615147Y565956
X637213Y582155
X615287Y594626
X608287Y618248
Y633248
Y648248
X603787Y651299
Y660748
Y670197
X608287Y688248
X639537Y689917
X608287Y698248
X639537Y700767
X647207Y709555
X608287Y718248
X642287Y719817
X608287Y728248
X637326Y732212
X637318Y749649
X615287Y766870
X631500Y774000
X603000Y781000
X642000Y889500
X604000Y897000
X646500Y898500
X632000Y936000
X634000Y988000
X638500Y1046500
X615287Y1047382
X645200Y1067800
X608287Y1071004
Y1086004
Y1101004
X603787Y1104055
Y1113504
Y1122953
X632603Y1136225
X608287Y1141004
X643000Y1146173
X608287Y1151004
X639537Y1153523
X647716Y1154150
X642942Y1156818
X636803Y1167864
X608287Y1171004
X600640Y1171000
X608287Y1181004
X647126Y1189513
X632316Y1190474
X637316
X627632Y1217300
X615238Y1218951
X673000Y1354100
X698500Y1306500
X664000Y1278100
X680500Y1208500
X650644Y1197038
X668000Y1195000
X650626Y1182447
X651216Y1164051
X667700Y1160173
X692671Y1152747
X694500Y1140173
X675500Y1125173
X671000
X680000
X685250Y1113673
X695000Y1107173
X685250Y1102873
X674700Y1098500
X696000Y1092973
X682200Y1026500
X663800Y1018300
X674300Y1001620
X688563Y961355
X693563
X677457Y944796
X658574Y930100
X654000Y911000
X692500Y790500
X691500Y778000
X678500Y776500
X673500Y752000
X650659Y744673
X650668Y720583
X650711Y710495
X670500Y707417
X694500Y699917
Y687417
X670929Y673058
X675429
X679929
X685550Y665417
X695000Y654417
X685550
X696000Y641717
X682000Y628449
X696787Y580633
X683341Y580479
X689747
X654681Y571798
X658681
X670000Y531500
X652663Y516600
X658646Y515180
X652663Y502400
X695500Y462500
X698500Y415500
X689172Y385976
X693112
X689172Y358978
X689232Y355251
X673500Y344000
X650000Y322500
X670500Y254661
X694500Y247161
X689426Y236628
X669813Y220374
X674313
X685545Y212806
X694950Y200846
X685250Y199493
X695137Y189130
X677450Y185669
X658500Y184500
X663449Y115606
X697483Y111500
X687566Y109568
X697457Y107247
X661965Y106177
X690807Y103298
X675000Y75500
X740000Y40000
X720000
X740000Y60000
X700000
X720000
X724645Y138941
X732500Y165492
X717188Y176461
X732500Y180492
X716600Y181161
X713350Y194661
X707700Y194861
X747242Y197553
X732100Y198373
X728000Y198543
X704950Y200846
X709950
X699950
X728000Y207992
Y217441
X731048Y238563
X732500Y245492
Y265492
Y275492
X710300Y276861
X716500Y300161
X738361Y306612
X724000Y338500
X748000Y368500
X726000Y369000
X732000Y374500
Y383000
X748500Y409000
X721500Y462500
X727500Y476000
X705348Y478425
X702500Y563000
X724000Y583500
X739500Y594626
X732500Y618248
X716600Y629417
X732500Y633248
X716600Y633917
X713350Y647417
X732500Y648248
X707700Y649117
X728000Y651299
X700000Y654417
X705000
X710000
X728000Y660748
Y670197
X704500Y672000
X732500Y688248
Y698248
Y718248
Y728248
X710300Y729617
X716500Y752917
X739500Y766870
X748000Y783000
X704500Y795000
X745000Y833000
X733422Y857828
X724283Y860689
X741883Y861389
X737984Y861689
X716233Y868219
X747656Y876717
X708683Y876958
X730882Y888502
X709500Y894500
X747383Y924689
X736883Y929189
Y933689
X733883Y935689
X736883Y938689
X733883Y940689
X736883Y943189
X736462Y948996
X712000Y1046000
X739500Y1047382
X732500Y1071004
X716600Y1081973
X732500Y1086004
X716600Y1086673
X713350Y1100173
X707700Y1100373
X732500Y1101004
X728000Y1104055
X705000Y1107173
X700000
X710000
X728000Y1113504
Y1122953
X716000Y1136000
X732500Y1141004
Y1151004
Y1171004
Y1181004
X710300Y1182373
X716500Y1205673
X739500Y1219626
X720446Y1267427
X722790Y1270557
X725678Y1272799
X728174Y1275611
X731500Y1277811
X748500Y1287500
X796848Y1469724
X784000Y1443000
X781000Y1373000
X772900Y1328550
X781290Y1328490
X785640Y1328370
X790290Y1328410
X769728Y1325747
X782230Y1323670
X777009Y1322690
X789549Y1322310
X785340Y1320410
X792336Y1319537
X769500Y1283500
X770000Y1231500
X756000Y1225500
X784544Y1210178
Y1205978
X752000Y1197500
X779535Y1193469
X797177Y1189537
X779535Y1189269
X797225Y1185337
X779535Y1184669
X792263Y1182861
X779535Y1180469
X792263Y1178661
Y1174461
Y1170261
X752500Y1167500
X756250Y1151750
Y1140250
X763000Y1075000
X759500Y1056100
X784000Y1024000
X786800Y1016000
X762500Y988500
X778000
X780800Y959300
X776400Y956500
X753883Y945689
Y937689
Y929689
X753893Y912630
X763883Y907689
X755883
X750883Y903689
X762453Y872413
X766707Y872260
X757664Y868974
X765025Y867802
X765124Y864089
X793000Y851000
Y828000
X751750Y685300
X755000Y677700
X754500Y668741
X798140Y630220
X798210Y626440
X798367Y622400
X787000Y514000
X772000Y479500
X767500Y463500
X764000Y439500
X789739Y365493
X771500Y311000
X752950Y213450
X767405Y210364
X763188Y172500
X758619Y168537
X757020Y159692
X760000Y60000
X780000
X799102Y48575
Y43575
X780000Y40000
X760000
X789045Y11615
X845661Y-3642
X833724Y-3346
X802362Y-458
X822047
X810236
X814173
X829921
X806299
X825984
X818110
X833671Y254
X843463Y530
X849484Y649
X802350Y35923
X806314Y35952
X841733Y36654
X838043Y37217
X818300Y39845
X814300
X802102Y41075
X842470Y41295
X838521Y41568
X818300Y43845
X814300
X802102Y46075
Y51075
X845961Y52762
Y56762
Y61762
X848769Y66957
X812801Y75654
X802801
X807801
X805301Y78654
X810301
X846000Y116500
X811500Y372000
X800000Y400000
X846400Y469300
X811500Y469500
X846400Y473900
X839500Y508500
X839000Y541000
X839500Y560000
X800867Y619400
X803367Y622400
X808920Y652340
Y656460
X804015Y661000
X809015
X806515Y664000
X827500Y922500
X803438Y1139700
X802036Y1164244
X827000Y1168000
X805000Y1191500
X810000
X802500Y1194500
X807500
X812500
X812100Y1233300
X802100
X807100
X804600Y1236300
X809600
X806952Y1460496
X802433Y1461619
X806568Y1464275
X800900Y1465234
X800462Y1469231
X839414Y1520763
X834813Y1528889
X834974Y1533243
X848551Y1542440
X897038Y1577600
X897400Y1574000
X893020Y1566530
X876200Y1558400
Y1553900
X889300Y1551000
X876100Y1549000
X866621Y1544206
X892700Y1543900
X876190Y1537187
X855092Y1535821
X892558Y1528458
X892700Y1524700
X892682Y1520718
X893158Y1516542
X876514Y1514948
X893036Y1512600
X892966Y1508549
X876096Y1505499
X863851Y1501681
X877828Y1500379
X877946Y1496527
X888800Y1493500
X860179Y1491170
X889002Y1489638
X893050Y1489500
X868791Y1478782
X873922Y1477766
X873972Y1472467
X882000Y1432600
X886500Y1432500
X877300Y1432400
X870921Y1432300
X872192Y1424492
X874900Y1421900
X871432Y1420932
X877406Y1419124
X873800Y1418200
X875740Y1415070
X873918Y1411149
X896200Y1405300
X873694Y1404575
X882226Y1404197
X886792Y1404100
X896100Y1401600
X896200Y1397900
X896100Y1393800
X895900Y1390100
X896200Y1386000
X873570Y1380401
X873700Y1375746
X885300Y1371050
X873495Y1370213
X873259Y1365805
X885301Y1358557
X872181Y1354764
X872164Y1350464
X884746Y1350438
X896212Y1345788
X896500Y1341800
X863800Y1309876
X898920Y1020000
X896371Y1002112
X895616Y985932
X896629Y982285
X895837Y978389
X898617Y975434
X899846Y971468
X895869Y932822
X896679Y927505
X896420Y916712
X898468Y912970
X882333Y896320
X877673Y868873
X873647Y861653
X885882Y861618
X894965Y843500
X888962Y843262
X897000Y839000
X891200Y838200
X870163Y836153
X865663Y834403
X885600Y824400
X867663Y818831
X887600Y811900
X874569Y811300
X878673Y804527
X870500Y762500
X891000Y743500
X874715Y707651
X867515
X871115
X881100Y705200
X884700
X877500
X877400Y688800
X884600
X881000
X871700Y685600
X868100
X875300
X868500Y665000
X877000Y664500
X867500Y643000
X860092Y542405
X855500Y499500
X851800Y477200
X870600Y476900
X878500Y476000
X878193Y467707
X871487Y463589
X866278Y459562
X866276Y454900
X857300Y454300
X852000Y454200
X862000Y453600
X866321Y451300
X866317Y446725
X856432Y410000
X877332
X852832
X880932
Y406400
X856432
X877332
X852832
X877332Y402800
X880932
X852832
X856432
X878732Y399200
X875132
X855032
X858632
Y395600
X855032
X878732
X875132
X878732Y392000
X875132
X855032
X858632
X887500Y378495
X874807Y375193
X856500Y373000
X887100Y359100
X874800Y355798
X890982Y349498
X881549Y326304
X866000Y315000
X898000Y268000
X850500Y266000
X888500Y260500
X872796Y251714
X898000Y133000
X853900Y89701
X885464Y83201
X878549Y82905
X882549Y80905
X878549Y78905
X886073Y78824
X882549Y76905
X856769Y74957
X852769
X852810Y71303
X856810
X873044Y70985
X861142Y71026
X869044Y70985
Y66985
X873044
X856769Y66957
X852769
X877139Y66926
X861101Y66680
X869459Y61626
X862099
X885265Y60540
X869459Y56626
X862099
X885265Y56540
X853961Y52762
X849961
X857961
X861961
X877265Y52540
X869265
X885265
X881265
X873265
X874244Y44935
X852995Y40965
X856995
X885448Y37380
X881750Y37397
X858496Y37121
X874244Y37026
X854180Y36996
X885046Y20384
X886427Y3802
X857513Y659
X867080Y393
X873892Y287
X886322Y69
X886351Y-3735
X886418Y-7350
X882000Y-105500
X910500Y-137500
X928600Y-115200
X902000Y-58000
X928138Y-8453
X922687Y93
X909000Y89000
X911000Y305500
X942000Y752850
X949048Y755225
X944500Y760750
X947866Y763541
X903000Y842500
X915000Y879000
X928100Y900650
X941274Y900845
X914876Y901029
X920810Y902210
X902571Y906534
X900615Y909723
X937621Y915324
X926185Y928342
X904594Y931141
X924974Y933041
X903368Y934568
X917550Y934742
X931085Y936172
X901540Y937712
X916204Y938572
X941868Y952101
X947174Y957150
X924563Y962945
X919759Y970868
X935623Y971054
X912994Y971921
X934142Y974344
X905271Y974586
X948942Y974655
X910397Y979189
X939481Y980230
X902991Y982230
X909826Y982874
X938009Y987330
X941640Y995820
X904601Y998556
X947759Y998726
X919656Y998764
X911807Y1002342
X903442Y1003265
X939544Y1003485
X946138Y1006299
X910040Y1006613
X946700Y1030700
X916446Y1035438
X936378Y1035722
X929257Y1035883
X904875Y1051177
X910387Y1055344
X908477Y1061823
X921149Y1062424
X914948Y1063255
X920770Y1067389
X906000Y1222000
X924500Y1236000
X932564Y1346100
X928384Y1346435
X936959Y1360143
X932559Y1360137
X928439Y1360167
X947125Y1369010
X942925
X936994Y1379895
X928194Y1379995
X932294
X923486Y1384268
X927601Y1384433
X923829Y1389012
X904941Y1456941
X909400Y1459200
X906600Y1461600
X910000Y1464900
X905500Y1467161
X908742Y1477427
X908542Y1481127
X932500Y1493200
X938000Y1499200
X946300Y1499300
X942000Y1499500
X918500Y1499700
X926500
X922500
Y1509700
X944921Y1515200
X900000Y1526500
X940000Y1529200
X918505Y1530405
X918800Y1534500
X906000Y1543700
X913250Y1547700
X948750Y1549200
X940750
X926500Y1556700
X945000Y1564200
X949000
X931500
X941000
X937000
X911516Y1573202
X911616Y1576802
X911710Y1582375
X911094Y1585923
X924059Y1647700
X962000Y1564200
X958000
X953500Y1563200
X975813Y1556916
Y1545916
X979963Y1545689
X972001Y1533926
X954700Y1530363
X974787Y1529300
Y1525100
X954700Y1524100
X969198Y1505851
X988624Y1502923
X969472Y1501978
X950300Y1499500
X951815Y1491459
X951525Y1369107
X955500Y1369000
X993500Y1317000
X962500Y1298500
X997500Y1192500
X995948Y1184250
X982387Y1183598
X977500Y1182300
X969463Y1177599
X963000Y1174427
X957871Y1171219
X967497Y1168802
X962941Y1165929
X958870Y1163617
X964537Y1160310
X972924Y1158033
X977400Y1157900
X954395Y1145604
X994923Y1137488
X996600Y1033743
X955700Y1030700
X951200
X968900Y1026200
X974020
X963780
Y1022400
X974020
X968900
X956600Y1005700
X992994Y1005740
X971460Y1005400
X966340
X961220
X987970Y1004157
X956600Y1001700
X966340Y1001600
X961220
X971460
X976580Y986180
X987734Y979575
X961134Y976191
X997694Y974940
X959400Y960300
X953013Y960147
X973900Y960000
X979020
X968780
Y956200
X973900
X979020
X976213Y938846
X966000Y937500
X981679Y936678
X960503Y936185
X974484Y935078
X953967Y933635
X967583Y933607
X981580Y932678
X961100Y931640
X976419Y931628
X968698Y928957
X976460Y927891
X962900Y905000
X957320Y769818
X952820Y769518
X957629Y766231
X952476Y753652
X956200Y748200
X951300Y747900
X957100Y742900
X952200Y742600
X956900Y737600
X953200Y736700
X977622Y699464
X977794Y695103
X978000Y677000
X993000Y635000
X985500Y613500
X974000Y523000
X995000Y488000
Y455000
X974000Y402000
X998000Y378000
X985688Y362549
X993000Y329000
Y157000
X993565Y137730
X990565Y135230
X993565Y132730
X990565Y130230
X993565Y127730
X990565Y125230
X993000Y108000
X975500Y11500
X992185Y-54411
X993000Y-60600
X999300Y-64400
X989050Y-70850
X998045Y-79300
X989316Y-94984
X993816Y-95184
X991713Y-115413
X981700Y-115500
X971713Y-115570
X986713
X976713
X1046713
X1041713Y-115465
X1036713Y-115500
X1004213Y-95837
X1012174Y-88726
X1034916Y-87913
X1011984Y-83066
X1034916Y-82413
X1045800Y-75936
X1000300Y-74200
X1019082Y-71000
X1000418Y-69982
X1015582Y-69800
X1043000Y-67600
X1035000Y-66800
X1014800Y-62100
X1009100Y-48600
X1032080Y-45980
X1023300Y-44200
X1007582Y-39418
X1004082Y-38200
X1022618Y-36900
X1032053Y-34953
X1043112Y-34912
X1038712Y-34812
X1019118Y-34382
X1043303Y-27685
X1045873Y-24660
X1043513Y-21696
X1021086Y-11682
X1026717Y-11646
X1010650Y49950
X1017600Y54200
Y58900
Y63600
X1010650Y67650
X1036003Y93543
X1041003
X1038503Y97543
X1033503
X1043703
Y102543
X1033503
Y107543
X1043703
X1033503Y112543
X1043703
X1030825Y122335
X1030758Y126274
X1030775Y130016
X1030774Y133840
X1030890Y137780
X1043500Y310500
X1048500Y346000
X1020250Y357188
X1045000Y364000
X1041500Y382858
X1045292Y384688
X1044600Y392500
Y397500
Y402500
Y407500
X1042833Y434409
X1040180Y437510
X1042800Y442000
X1043500Y446600
X1043674Y451921
X1047000Y492000
X1018322Y545207
X1018300Y550000
X1045106Y561249
X1047000Y751000
X1025000Y817000
X1028472Y834829
X1045163Y840400
X1027063Y850703
X1031563Y852453
X1034271Y876911
X1038215Y877191
X1025000Y897700
X1043882Y901568
X1011100Y904600
X1016842Y916445
X1044680Y921400
X1044101Y927130
X1036431Y929752
X1037083Y933300
X1014891Y943357
X1035947Y948800
X1013713Y974651
X1037282Y995028
X1041616Y997225
X1010414Y997940
X1005294
X1025774Y1001538
X1010414Y1001740
X1005294
X1023214Y1007140
X1013700Y1007640
X1028657Y1009103
X1009509Y1009850
X1018094Y1021240
X1012974
X1048512Y1021378
X1007372Y1023832
X1015534Y1023840
X1020654Y1023940
X1007849Y1033743
X1017194Y1033840
X1012494
X1032500Y1067100
X1037000
X1018000Y1076500
X1036160Y1091700
X1048960
X1041280
X1017000Y1093950
X1021200Y1094300
X1036160Y1095500
X1041280
X1048960
Y1099300
X1041280Y1100500
X1036160Y1111900
X1048960Y1113900
X1041280
Y1117700
X1048960
X1041280Y1121500
X1031400Y1124700
X1022400Y1129183
X1026900Y1129466
X1013400Y1137500
X1004294Y1137600
X1021991Y1141526
X1046900Y1168000
X1019000Y1178000
X1006800Y1191200
X1017354Y1196124
X1021061Y1198543
X1032500Y1248000
X1047000Y1258687
X1016835Y1323916
X1042343Y1324216
X1025335
X1042343Y1330916
X1025335
X1016600Y1332000
X1025335Y1337616
X1042343
X1016672Y1338228
X1025284Y1341216
X1042443Y1342668
X1048251Y1349992
X1031000Y1350500
X1031474Y1354526
X1046372Y1356326
X1028000Y1404700
X1031500Y1408000
X1028000Y1411000
X1033000Y1416125
X1044654Y1455075
X1020854
X1048654
X1016854
X1092927Y1558887
X1096547
Y1555087
X1092927
X1095938Y1535420
X1090818
Y1531620
X1095938
X1072754Y1455075
X1076754
X1079500Y1276100
X1077300Y1271700
X1051300Y1253300
X1076032Y1191144
X1070000Y1184100
X1075600Y1179090
X1053743Y1174221
X1052522Y1145153
X1083355Y1125903
X1070155
X1092200Y1125800
X1087700
X1054080Y1117700
X1070155Y1116103
X1083355
X1096460Y1115125
X1054080Y1113900
X1092742Y1113462
X1099020Y1112276
X1068700Y1108700
Y1096600
X1064500Y1096150
X1081078Y1095362
X1083660Y1092700
X1054080Y1077680
X1091494Y1075994
X1097500Y1075100
X1091400Y1070900
X1097800Y1070700
X1073500Y1067100
X1069000
X1082500
X1052000Y1054000
X1072000Y1035000
X1053099Y1021657
X1058571Y943852
X1073408Y942399
X1083633Y932172
X1053200Y901703
X1054000Y866000
X1075500Y848000
X1054419Y839493
X1089300Y836100
X1086600Y833200
X1050763Y829163
X1054419Y828081
X1082000Y815500
X1073000Y676000
X1058000Y616000
X1079000Y477000
X1058000
X1065985Y460500
X1069018Y456900
X1071950Y453288
X1074425Y447225
X1050100Y407600
X1078100
X1072600Y407500
X1078100Y402600
X1050100
X1072600Y402500
X1050100Y397600
X1078100
X1072600Y397500
X1078100Y392600
X1050100
X1072600Y392500
X1058500Y368500
X1078500Y135500
Y99000
X1062854Y83434
X1077400Y52000
X1076905Y46195
X1077260Y42612
X1077082Y38982
X1076944Y35182
X1076418Y31082
X1076299Y27282
X1054800Y22405
X1077505
X1076000Y-10500
X1079455Y-30742
X1087700Y-37886
X1094200Y-38400
X1074400Y-39100
X1054625Y-40278
X1066225
X1061325Y-40378
X1078900Y-45782
X1079600Y-50700
X1054593Y-51122
X1085800Y-57100
X1094300Y-60300
X1093900Y-64500
X1070500Y-67900
X1058333Y-72770
X1066600Y-72800
X1070918Y-73618
X1074400Y-81000
X1084200Y-82300
X1097600Y-82462
X1065621Y-85082
X1085300Y-90700
X1089318Y-91682
X1051713Y-114887
X1056713Y-115413
X1066713Y-115570
X1076713
X1086713
X1071713
X1081713
X1117535Y-115157
X1134500Y-103500
X1106300Y-94800
X1100929Y-90371
X1116600Y-85538
X1115000Y-77500
X1107700Y-76800
X1115603Y-60293
X1103300Y-60000
X1139500Y-58500
X1114400Y-55662
X1113300Y-44100
X1142293Y-37522
X1149699Y-35153
X1128765Y-34297
X1139808Y-31171
X1146768Y-31238
X1101246Y-31005
X1105328
X1111254Y-31020
X1124024Y-30840
X1136203Y167600
X1140500Y171400
X1142800Y174637
X1134110Y176500
X1140550Y179200
X1138198Y832424
X1119159Y868130
X1116159Y870630
X1119159Y873130
X1116159Y875630
X1119159Y878130
X1119419Y888607
X1116419Y891107
X1119419Y893607
X1116419Y896107
X1119419Y898607
X1108347Y902617
X1103347
X1110847Y905617
X1105847
X1100847
X1100447Y944217
X1105447
X1110447
X1107947Y947217
X1102947
X1128900Y1067200
X1124500
X1119700
X1103800Y1070600
Y1075600
X1144580Y1078680
X1101580Y1091120
X1134002Y1092600
X1123838Y1092800
X1107100Y1096050
X1133981Y1096283
X1123600Y1096400
X1111600Y1097800
X1134103Y1099881
X1123600Y1100000
X1103064Y1113626
X1143550Y1120317
X1139524Y1121817
X1137436Y1124750
X1124100Y1125100
X1128800
X1115000
X1119500
X1149823Y1233373
X1144000Y1310000
X1147900Y1421500
X1145007Y1424446
X1148556Y1425056
X1142400Y1427700
X1146002Y1427906
X1143900Y1431000
X1134100Y1433300
X1141000Y1632000
X1163000Y1612000
X1194000Y1499000
X1153000Y1496000
X1150911Y1329500
X1154500Y1327500
X1150232Y1316358
X1181400Y1266100
X1184000Y1260100
X1150420Y1229800
X1152800Y1223062
X1152700Y1216213
X1198130Y1151410
X1172564Y1118373
X1149984Y1115804
X1152880Y1097672
X1152682Y1091138
X1170140Y1043939
X1194000Y1037900
X1177036Y1032086
X1172736Y1031786
X1192000Y869000
X1158500Y868500
X1166500Y829500
X1179000
X1181000Y814000
X1156500Y813000
X1188000Y753000
X1194268Y730300
X1197868
X1169768
X1173368
X1194268Y726700
X1197868
X1169768
X1173368
Y723100
X1194268
X1197868
X1169768
X1195668Y719500
X1192068
X1175568
X1171968
X1175568Y715900
X1171968
X1192068
X1195668
Y712300
X1175568
X1171968
X1192068
X1156500Y650000
X1166500Y635000
X1156500Y619000
X1176835Y618934
X1156500Y467000
X1173500Y397000
X1189700Y308527
X1193800Y307857
X1198100Y306858
X1176300Y288600
X1194600Y288237
X1190200Y285023
X1185588Y285035
X1180953Y284800
X1176300Y284500
X1185000Y281343
X1174037
X1197000Y279400
X1176100Y270603
X1194700Y261700
X1171749Y259163
X1175400Y258800
X1182590Y254388
X1186600Y253200
X1186500Y220500
X1177500Y153500
X1178656Y104637
X1184088Y101360
X1184141Y96794
X1176952Y93390
X1199768Y89368
X1178268Y89068
X1183268
X1188268
X1199768Y85368
X1178268Y85068
X1188268
X1183268
X1199768Y69368
X1188268Y69068
X1183268
X1178268
X1199768Y64368
X1183268Y64068
X1178268
X1188268
X1181568Y60168
Y55168
X1181868Y50568
Y45568
X1150000Y-63000
X1228500Y12500
X1240500Y20000
X1204068Y45368
Y50368
X1203768Y55568
Y60568
X1204768Y64368
X1209768
X1204768Y69368
X1209768
X1204768Y85368
X1209768
Y89368
X1204768
X1224000Y104000
X1215795Y181242
X1224800Y225200
X1219917Y239646
X1248193Y242618
X1219962Y244739
X1215547Y246355
X1215600Y261800
X1201835Y305319
X1226045Y431102
X1235796Y517450
X1239362Y524168
X1232500Y541000
X1243200Y933700
X1232700Y950400
X1239900Y1024000
X1240314Y1139741
X1232842Y1140722
X1246557Y1148155
X1229691Y1148580
X1249600Y1155800
X1205303Y1227604
X1220500Y1311000
X1214500Y1320500
X1240276Y1356700
X1263500Y1318500
X1257000Y1300000
X1254800Y1269600
X1289106Y1219626
X1282106Y1181004
Y1171004
X1260300Y1169000
X1282106Y1151004
X1268948Y1150173
X1251250Y1141700
X1282106Y1141004
X1272755Y1137293
X1277606Y1122953
Y1113504
Y1104055
X1282106Y1101004
Y1086004
X1279081Y1071085
X1252400Y1054100
X1289114Y1048624
X1256142Y1029316
X1268378Y990608
X1263618Y990606
X1271296Y986867
X1274413Y984613
X1286000Y982200
X1264269Y981248
X1253338Y980784
X1279599Y976407
X1253975Y970147
X1250475Y969248
X1284695Y956586
X1259808Y927260
X1263250Y823436
X1289106Y766870
X1298500Y752417
X1282106Y728248
Y718248
X1268400Y716100
X1265891Y699583
X1282106Y698248
X1253800Y689600
X1282106Y688248
X1277606Y670197
Y660748
Y651299
X1282106Y648248
Y633248
Y618248
X1289106Y594626
X1253511Y517606
X1250011Y516707
X1264878Y508068
X1287000Y456000
X1280000Y430000
X1289000Y309500
X1298500Y302900
X1262075Y297100
X1276200Y277400
X1298700Y272800
X1250500Y266600
X1273200Y263700
X1250016Y247017
X1282287Y243489
X1255600Y237300
X1282106Y235492
X1253300Y227700
X1277606Y217441
X1278421Y205974
X1281603Y203340
X1297507Y195492
X1282106Y180492
X1280800Y167200
X1289000Y145400
X1254000Y105000
X1281500Y103500
X1299569Y100639
Y84272
X1319000Y12000
X1347500Y21000
X1318500Y34500
X1309000Y45500
X1328295Y55800
X1323829Y55929
X1332500Y56500
X1320055Y68000
X1334383Y75892
X1319100Y78800
X1340961Y78811
X1327921Y78900
X1323521Y79179
X1346081Y80671
X1336034Y82542
X1348641Y83326
X1304563Y84309
X1333281Y85133
X1343521Y85472
X1308228Y93399
X1312263Y95463
X1315961Y98112
X1304563Y100771
X1347607Y101337
X1341922Y105649
X1312999Y107280
X1338215Y107586
X1317661Y107896
X1348641Y110550
X1313127Y120839
X1338400Y126015
X1324134Y126967
X1315118
X1343112Y128997
X1337662Y137188
X1332934Y137712
X1315102Y137903
X1349931Y138361
X1324207Y138756
X1333988Y161471
X1314794Y162944
X1304293Y165909
X1311200Y172661
X1330807Y181473
X1302074Y183779
X1311750Y187911
X1315838Y188804
X1334500Y202548
Y207548
Y212548
Y217548
X1321637Y226568
X1326637
X1316637
X1313915Y263541
X1305000Y299400
X1313000Y302900
X1311000Y321000
X1303500Y434000
X1346363Y516578
X1332148Y517321
X1338100Y520300
X1346057Y529857
X1338000Y546500
X1337500Y576500
X1310000Y597000
X1307500Y615417
X1312000
X1311200Y625417
X1336000Y627000
X1326500Y627917
X1303800Y636417
X1311750Y640667
X1315400Y648017
X1334000Y652917
Y657417
Y661917
Y666417
X1323000Y680417
X1318000
X1328000
X1314000Y717417
X1302500Y718917
X1347600Y734078
X1344062Y737800
X1305000Y752417
X1313000
X1334300Y771200
X1338700Y771500
X1316000Y772200
X1310500Y774700
X1334329Y775831
X1338729Y776131
X1339500Y794000
X1312767Y885535
X1346080Y907004
X1341219Y933282
X1331070Y966090
X1348796Y969488
X1339404Y969600
X1344000Y987500
X1349829Y1014840
X1305000Y1041500
X1317400Y1068000
X1305100Y1068173
X1309600
X1311200Y1078173
X1326500Y1080673
X1303800Y1089173
X1311750Y1093423
X1315300Y1100773
X1334500Y1104700
Y1111173
Y1116173
Y1121173
X1328000Y1133173
X1318000
X1323000
X1313950Y1165990
X1302500Y1171673
X1305000Y1205173
X1313000
X1300065Y1206008
X1365551Y1353500
X1369600Y1330100
X1373700Y1330000
X1381800Y1329600
X1386500Y1258000
X1387000Y1243500
X1355733Y1241900
X1388500Y1224900
X1383899Y1166690
X1351321Y1152553
X1370716Y1148037
X1360238Y1143867
X1364713Y1143791
X1375463Y1142673
X1365461Y1136100
X1368935Y1123365
X1361074Y1114565
X1385494Y1113504
X1390500Y1048000
X1365551Y1028250
X1384800Y1002666
X1362000Y987000
X1378100Y972100
X1353762Y969886
X1362382Y961355
X1367382
X1390000Y955500
X1391000Y932400
X1380300Y930200
X1392355Y886696
X1395000Y791500
X1398245Y766870
X1373519Y761900
X1360920Y749829
X1354500Y747304
X1383952Y717435
X1373553Y700994
X1375463Y689917
X1359700Y587600
X1355700
X1396297Y579803
X1372272Y573560
X1396297Y573397
X1357316Y542311
X1353500Y518900
X1396500Y511000
X1383500Y509500
X1364882Y508014
X1359882
X1385000Y480000
X1395300Y438500
X1375700Y413400
X1372000Y335000
X1384713Y323200
X1398493Y314114
X1374338Y292900
X1358573Y290900
X1355991Y275272
X1372274Y272874
X1384475Y255839
X1377463Y237100
X1385051Y218684
X1394705Y195413
X1362685Y130109
X1358971Y129978
X1351665Y128325
X1364017Y123277
X1350779Y106496
X1352351Y101724
X1351201Y90099
X1358355Y81488
X1354500Y75400
X1351200Y68600
X1359350Y66350
X1357500Y43500
X1413268Y146062
X1436204Y159247
X1431713Y162661
X1405100Y166000
X1427663Y167032
X1445994Y174086
X1406319Y180492
X1435963Y183833
X1428013Y185956
X1440300Y188000
X1401819Y207992
X1447213Y227661
X1442213
X1406000Y236700
X1403963Y245492
X1438186Y261287
X1406319Y265492
X1426713Y266161
X1406319Y275492
X1439300Y301500
X1429800Y302500
X1426400Y307400
X1447170Y337890
X1439654Y349852
X1444238
X1431909Y359311
X1441770Y365790
X1427000Y380000
X1414882Y397271
X1441970Y403990
X1400000Y406000
X1439500Y421500
X1418225Y421700
X1440000Y460000
X1405000
X1425000Y480000
X1405000
X1449576Y495482
X1448261Y515000
X1435200
X1439200
X1443700
X1418507Y517007
X1414319Y523900
X1448450Y529600
X1418493Y531407
X1425200Y540100
X1425600Y544600
X1407936Y548099
X1442500Y548400
X1407936Y552099
X1442500Y554700
X1421239Y558029
Y562229
X1413400Y575000
X1447700Y579600
X1413319Y594626
X1436213Y615417
X1431713
X1406319Y618248
X1435413Y625417
X1406319Y633248
X1428013Y636417
X1435963Y640667
X1439713Y647917
X1406319Y648248
X1401819Y651299
Y660748
X1421500Y664000
X1401819Y670197
X1442213Y680417
X1447213
X1406319Y688248
X1449000Y698000
X1406319Y698248
X1438087Y713756
X1406319Y718248
X1426713Y718917
X1406319Y728248
X1429213Y752417
X1422713
X1437213
X1432000Y831000
X1433500Y864500
X1435300Y882700
X1440500Y893500
X1448000Y910000
X1440000Y986500
X1433500Y1044000
X1413319Y1047382
X1446213Y1062300
X1431713Y1068173
X1436213
X1406319Y1071004
X1435413Y1078173
X1406319Y1086004
X1428013Y1089173
X1439750Y1096673
X1439713Y1100773
X1406319Y1101004
X1401819Y1104055
Y1122953
X1447213Y1132173
X1442213
X1406319Y1141004
Y1151004
X1438213Y1170173
X1406319Y1171004
X1426713Y1171673
X1406319Y1181004
X1422713Y1205173
X1429213
X1437213
X1413319Y1219626
X1413000Y1241500
X1418000Y1291500
X1440000Y1320000
X1420000
X1400000
X1491662Y1351300
X1497200Y1342500
X1494662Y1336000
X1480000Y1320000
X1460000
Y1300000
X1458000Y1265500
X1473600Y1242777
X1467000Y1221800
X1475953Y1152427
X1470953
X1495900Y1149000
X1489333Y1147664
X1499675Y1142673
X1485833Y1140369
X1452213Y1132173
X1489096Y1131456
X1461713Y1123173
X1489108Y1121674
X1461713Y1118173
X1485608Y1113628
X1461713Y1113173
X1461700Y1107200
X1488500Y1096000
X1450713Y1080673
X1456000Y1044000
X1481529Y1030500
X1478194Y1017166
X1451800Y1004700
X1481500Y995758
X1484000Y992315
X1457500Y987500
X1477974Y970044
X1473008Y969646
X1458967Y969535
X1463616Y969265
X1491594Y961355
X1486594
X1499500Y831000
X1459500Y814000
X1450500Y802500
X1473000Y798000
X1459500Y796500
X1486600Y786559
X1499500Y774000
X1471608Y768500
X1474083Y764750
X1479033Y762259
X1476558Y759088
X1498000Y743000
X1489000Y723000
X1495480Y704558
X1494462Y692179
X1452213Y680417
X1458713Y668417
Y663417
Y658417
Y652217
X1450713Y627817
X1455202Y618557
X1460274Y592498
X1464700Y585600
X1470000Y580000
X1452200Y579600
X1459200
X1478700Y579100
X1474700
X1455750Y572350
X1474700Y569100
X1452279Y563600
X1494400Y560400
Y556100
X1457200Y549600
X1497849Y545264
X1479212Y535612
X1456450Y529600
X1494100Y526400
X1485932Y522335
X1470700Y522100
X1460200Y515000
X1456439
X1452200
X1465700
X1481938Y512568
X1491594Y508098
X1486594
X1468605Y493549
X1463000Y490638
X1481938Y489926
X1461300Y404200
X1461100Y366000
X1466500Y338100
X1463000Y307000
X1499775Y248061
X1498900Y235800
X1452213Y227661
X1458764Y217225
Y212625
Y208025
Y203425
X1450713Y173049
X1456373Y168971
X1463804Y138605
X1511177Y125412
X1525336Y149369
X1545383Y164116
X1530531Y180492
Y195492
X1526031Y198543
Y207992
Y217441
X1530142Y238021
X1530531Y245492
Y265492
Y275492
X1546925Y299661
X1537531Y314114
X1508925Y323200
X1505000Y378500
X1520000Y421500
X1525000Y455000
X1545000
Y475000
X1509800Y516100
X1513200Y519700
X1500600Y523300
X1507900Y539100
X1502400Y544100
X1509911Y553511
X1502400Y554100
X1537531Y594626
X1530531Y618248
Y633248
Y648248
X1526031Y651299
Y660748
Y670197
X1530531Y688248
Y698248
X1505900Y717600
X1530531Y718248
X1526000Y728000
X1530531Y728248
X1500539Y739639
X1546925Y752417
X1537531Y766870
X1520000Y776000
X1515000Y789000
X1510000Y860500
X1510500Y878000
X1525000
X1521200Y928000
X1505900Y930400
X1548500Y933000
X1512500Y949000
X1503394Y968179
X1508500Y1028500
X1537531Y1047382
X1508500Y1050500
X1530531Y1071004
Y1086004
X1547800Y1098819
X1530531Y1101004
X1526031Y1104055
Y1113504
Y1122953
X1528723Y1138918
X1530531Y1151004
Y1171004
X1504200Y1171300
X1530531Y1181004
X1546898Y1204827
X1537879Y1219626
X1501600Y1342300
X1581500Y1240000
X1558650Y1217426
X1553425Y1208897
X1561425Y1205173
X1593500Y1185500
X1550925Y1171673
X1562425Y1170173
X1552575Y1139700
X1556231Y1134920
X1598425Y1107440
Y1102440
X1552800Y1098819
X1557800
X1562800
X1552225Y1089173
X1574925Y1080673
X1559625Y1078173
X1555925Y1068173
X1560425
X1570425Y1062000
X1557500Y1043500
X1593000
X1552500Y1028000
X1580381Y1007066
X1596000Y990000
X1574576Y976700
X1597221Y969572
X1583180Y969461
X1587829Y969191
X1564000Y949000
X1564500Y931000
X1576500Y928500
X1587400Y912200
X1584800Y895800
X1570500Y888400
X1580000Y780000
X1555000Y770000
X1561425Y752417
X1553425
X1550925Y718917
X1562425Y717417
X1571425Y677417
X1566425
X1576425
X1565618Y670773
Y665773
Y660773
X1565593Y654856
X1558925Y650017
X1555175Y642667
X1552225Y636417
X1574925Y627817
X1559625Y625417
X1578926Y618657
X1560425Y615417
X1555925
X1566000Y595000
X1552000Y584500
X1573000Y565500
X1568000Y548500
X1568500Y544100
X1560000Y525000
X1586596Y518723
X1583030Y517405
X1597245Y516662
X1560000Y500000
Y475000
Y455000
X1568500Y438500
X1579500Y331000
X1561425Y299661
X1553425
X1550925Y266161
X1562425Y264661
X1595500Y258500
X1571425Y227661
X1576425
X1566425
X1582925Y215661
Y210661
Y205661
Y200661
X1563925Y195261
X1560175Y187911
X1552225Y183661
X1574925Y175061
X1559625Y172661
X1579371Y166019
X1560425Y162661
X1555925
X1560000Y140000
X1585757Y134147
X1580000Y80000
Y60000
Y40000
Y20000
X1640000
X1620000
X1600000
X1640000Y40000
X1600000
X1620000
X1600000Y60000
X1640000
X1620000Y80000
X1640000
X1600000
X1640000Y100000
X1620000
X1640000Y120000
X1620000
Y140000
X1607000Y199000
X1621100Y240561
Y244661
X1608000Y256000
X1622738Y264938
X1639000Y320000
X1600000
X1620000
Y340000
X1640000
X1600000
X1640000Y360000
Y460000
Y480000
Y500000
X1615807Y508600
X1610807
X1600745Y517561
X1640000Y520000
Y540000
Y560000
X1623888Y689917
X1620469Y697517
X1621138Y719238
X1637000Y729000
X1638000Y740000
X1630000Y760000
Y780000
X1625000Y800000
X1646013Y884255
X1643344Y887455
X1639644Y889755
X1608200Y914400
X1618200Y916800
X1621787Y917108
X1636400Y925800
X1633600Y936300
X1615807Y961355
X1610807
X1602187Y969970
X1615494Y973179
X1629094Y975179
X1602400Y1019366
X1620059Y1032932
X1632000Y1049500
X1611500Y1078000
X1603425Y1100040
Y1105040
X1627769Y1110037
X1624198Y1111309
X1627802Y1118949
X1620059Y1128071
X1627563Y1132075
X1635688Y1141158
X1627197Y1143044
X1615909Y1150262
X1635688Y1153773
X1633138Y1165673
X1613400Y1236500
X1640000Y1260000
Y1280000
Y1300000
X1600000Y1320000
X1640000
X1624500Y1349100
X1680000Y1320000
X1660000
X1680000Y1300000
X1660000
Y1280000
X1680000
X1660000Y1260000
X1680000
Y1240000
X1661744Y1219626
X1685638Y1205173
X1671138
X1677638
X1668378Y1181004
X1675138Y1171673
X1686638Y1170173
X1650841Y1168660
X1654744Y1151004
Y1141004
X1690638Y1131673
X1695638
X1650244Y1122953
Y1113504
Y1104055
X1654744Y1101004
X1688138Y1100773
X1684388Y1091723
X1676438Y1089173
X1654744Y1086004
X1699138Y1080573
X1683838Y1078173
X1654744Y1071004
X1680138Y1068173
X1684638
X1694638Y1063600
X1685100Y1054000
X1661744Y1047382
X1679300Y1043169
X1691771Y1035163
X1680087Y1023983
X1653500Y1016500
X1685047Y1014966
X1690279Y1011526
X1671422Y1009266
X1650000Y1000000
Y980000
X1674814Y961977
X1677056Y954636
X1680012Y952402
X1650000Y950000
X1692100Y923600
X1651500Y913500
X1687000Y905500
X1685000Y770000
X1661744Y766870
X1677638Y752417
X1671138
X1685638
X1654744Y728248
X1675138Y718917
X1654744Y718248
X1686638Y717417
X1654744Y698248
Y688248
X1699638Y675417
X1694638
X1689638
X1652962Y670204
X1650244Y660748
Y651299
X1654744Y648248
X1688138Y648017
X1684388Y638324
X1676438Y636417
X1654744Y633248
X1699138Y627917
X1683838Y625417
X1654744Y618248
X1684638Y615417
X1680138
X1661744Y594626
X1660000Y560000
X1680000
X1660000Y540000
X1680000
X1660000Y520000
X1680000
Y500000
X1660000
X1680000Y480000
X1660000
Y460000
X1680000
Y440000
X1660000
X1680000Y420000
X1660000Y400000
X1680000Y380000
X1660000Y340000
X1678500Y320000
X1661744Y314114
X1677638Y299661
X1671138
X1685638
X1652387Y277343
X1653789Y267766
X1675475Y267424
X1686638Y264661
X1654744Y245492
Y235492
X1690638Y227661
X1695638
X1650244Y217441
Y207992
Y198543
X1654744Y195492
X1688138Y195261
X1684388Y187911
X1676438Y183661
X1654744Y180492
X1699138Y175061
X1683838Y172661
X1654744Y165492
X1680138Y162661
X1684638
X1679500Y144000
X1661744Y141870
X1680000Y120000
X1660000
Y100000
X1680000
Y80000
X1660000
Y60000
X1680000
Y40000
X1660000
X1680000Y20000
X1660000
X1720000
X1700000
X1740000
Y40000
X1700000
X1720000
X1700000Y60000
X1720000
X1740000
Y80000
X1700000
X1720000
X1740000Y100000
X1720000
X1700000
X1740000Y120000
X1720000
X1700000
X1740000Y140000
X1720000
X1700000
X1703584Y166019
X1707138Y200661
Y205661
Y210661
Y215661
X1700638Y227661
X1746600Y240561
X1746400Y244561
X1728500Y249500
X1747550Y265000
X1720000Y280000
Y300000
X1740000Y320000
X1720000Y340000
X1700000Y360000
Y400000
Y420000
Y440000
Y460000
X1740019Y508600
X1735019
X1721710Y516409
X1707495Y517152
X1711061Y518470
X1725100Y519300
X1700000Y540000
X1740000
X1700000Y560000
X1705000Y618667
X1707100Y652500
X1707138Y658417
X1745000Y660000
X1707138Y663417
Y668417
X1730000Y670000
X1745000
X1730000Y690000
X1745000
X1730000Y710000
Y730000
Y750000
X1710000Y770000
X1730000Y775000
X1735000Y785000
X1710000
X1725000Y800000
X1718000Y876000
X1704010Y898000
X1709000Y915000
X1716500Y943500
X1735019Y961355
X1740019
X1742001Y965464
X1738863Y985225
X1740363Y989225
X1737241Y997843
X1726681Y1001554
X1712181
X1719681
X1749863Y1003925
X1746030Y1004209
X1717681Y1006054
X1740499Y1008223
X1722181Y1009054
X1706000Y1022000
X1725000Y1045000
X1745000Y1100000
X1707200Y1105200
X1707138Y1111173
X1733245Y1115503
X1707138Y1116173
Y1121173
X1736725Y1123446
X1700638Y1131673
X1732768Y1141697
X1736941Y1141871
X1748100Y1142673
X1718117Y1152553
X1723117
X1748100Y1153673
X1736871Y1158178
X1728000Y1204500
X1702838Y1215300
X1710617Y1231429
X1715049Y1234000
X1700000Y1260000
Y1280000
Y1300000
X1720000Y1320000
X1700000
X1740000Y1346900
X1760000Y1320000
X1753000Y1302000
X1772111Y1232695
X1785956Y1219626
X1755900Y1212704
X1795350Y1205173
X1778956Y1181004
X1751400Y1173900
X1799350Y1171673
X1778956Y1171004
Y1151004
Y1141004
X1774456Y1122953
X1759055Y1113504
X1774456Y1104055
X1778956Y1101004
Y1086004
Y1071004
X1785956Y1047382
X1755000Y1045000
X1788726Y1034726
X1774863Y1024725
X1763714Y1015491
X1755900Y1014600
X1787163Y1009741
X1778863Y1005725
X1772863Y1005304
X1756100Y1004362
X1757600Y999200
X1753600
X1761600
X1778963Y999125
X1772263Y995925
X1757600Y995200
X1753600
X1761600
X1757600Y991200
X1761600
Y987200
X1757600
X1761600Y983200
X1757600
X1783778Y970371
X1759884Y969161
X1797463Y968652
X1755010Y966285
X1768692Y966073
X1788361Y964676
X1799051Y963346
X1782666Y961344
X1777666
X1799000Y945500
X1771000Y944500
X1752000Y929200
X1773500Y879500
X1785956Y766870
X1795468Y752594
X1778956Y728248
X1766721Y720500
X1778956Y718248
X1799326Y717506
X1766721Y716500
X1778956Y698248
Y688248
X1774456Y670197
Y660748
Y651299
X1778956Y648248
Y633248
Y618248
X1785956Y594626
X1760000Y540000
X1780000
Y520000
X1760000
X1780000Y500000
X1760000
Y480000
X1780000
X1760000Y460000
X1780000
Y440000
X1760000
Y420000
Y340000
X1785956Y314114
X1795350Y299661
X1763500Y288000
X1778956Y275492
X1799350Y266161
X1778956Y265492
Y245492
Y235492
X1760486Y217441
X1774456Y207992
Y198543
X1778956Y195492
Y180492
X1775140Y165728
X1785956Y141870
X1780000Y120000
X1760000
X1780000Y100000
X1760000
X1780000Y80000
X1760000
X1780000Y60000
X1760000
X1780000Y40000
X1760000
Y20000
X1800000Y80000
Y100000
X1840000
X1820000
Y120000
X1800000
X1840000
X1820000Y140000
X1841021Y152968
X1845517Y158475
X1808850Y162661
X1804350
X1827796Y166019
X1808050Y172661
X1823350Y175161
X1801988Y183904
X1808600Y187911
X1812350Y195261
X1831350Y200661
Y205661
Y210661
Y215661
X1841669Y219661
X1846169
X1824850Y227661
X1819850
X1814850
X1841169Y254661
X1810850Y264661
X1801850Y299661
X1809850
X1820000Y320000
X1840000
Y340000
X1800000Y440000
X1820000
X1800000Y460000
X1820000
Y480000
X1800000
Y500000
X1845545Y516536
X1831330Y517279
X1849045Y517435
X1834896Y518597
X1800000Y520000
Y540000
X1840000
X1820000
X1840000Y560000
X1820000
X1800000
X1820000Y580000
X1840000
X1840855Y606200
X1845417Y611231
X1808850Y615417
X1804350
X1827667Y618703
X1808050Y625417
X1823350Y627917
X1800650Y636417
X1808600Y640667
X1812350Y648017
X1831300Y652600
X1831350Y658417
Y663417
Y668417
X1846169Y672417
X1841669
X1819850Y680417
X1824850
X1814850
X1837576Y707417
X1811474Y717423
X1809968Y752594
X1801968
X1820000Y780000
X1848491Y807787
Y811787
Y815787
Y819787
Y823787
X1838311Y827911
X1845651Y828016
X1838239Y831626
X1845579Y831731
X1824170Y886349
X1823937Y890883
X1821152Y907899
X1819541Y921500
X1813851Y927406
X1843731Y936066
X1843811Y940067
X1830665Y941751
X1836165
X1825945Y945449
X1840419Y945557
X1825945Y950949
X1840419Y951057
X1806077Y961860
X1849363Y1002625
X1845363
X1825971Y1010012
X1840445Y1010120
X1825971Y1015512
X1840445Y1015620
X1830395Y1020064
X1835895
X1805250Y1067973
X1800750
X1812050Y1071223
X1808050Y1078173
X1823350Y1080673
X1800650Y1089173
X1816046Y1098532
X1811968Y1100773
X1836953Y1103391
X1828850Y1106173
Y1111173
Y1116173
X1847506Y1118794
X1828850Y1121173
X1836200Y1130000
X1814850Y1133173
X1819850
X1824850
X1836231Y1140669
X1840585Y1151653
X1836400Y1151900
X1810850Y1170173
X1809850Y1205173
X1801850
X1842000Y1344700
X1873500Y1329000
X1860000Y1320000
X1887169Y1205673
X1880969Y1182373
X1850532Y1153286
X1864352Y1153308
X1871174Y1138730
X1863131Y1133108
X1898669Y1122953
X1851565Y1118784
X1850363Y1115037
X1898669Y1113504
X1850280Y1111373
X1856437Y1106400
X1898669Y1104055
X1858046Y1092779
X1880779Y1091763
X1875779
X1870779
X1864833Y1091419
X1863700Y1085000
X1871000Y1073300
X1884835Y1067400
X1888085Y1059938
X1872162Y1055426
X1868100Y1055410
X1876662Y1055426
X1887402Y1050193
X1864617Y1040934
X1853363Y1002625
X1861363
X1865363
X1857363
X1867963Y996425
X1880122Y954062
X1875769Y951122
X1880383Y950341
X1875801Y946796
X1872190Y936766
X1876276Y920059
X1872276
X1891676Y917759
X1876276Y916059
X1872276
X1860276
X1864276
X1868276
X1884500Y912500
X1868276Y912059
X1876276
X1860276
X1864276
X1872276
X1873001Y901396
X1884200Y895000
X1896943Y894350
X1892443
X1884800Y890750
X1850177Y838746
X1850151Y835119
X1855676Y800787
X1880000Y780000
X1887169Y752917
X1850000Y745000
X1880969Y729617
X1865169Y699917
X1862200Y686700
X1850669Y672417
X1898669Y670197
X1856219Y665417
X1898669Y660748
X1856219Y654417
X1864669Y652917
X1869669
X1874669
X1879669
X1898669Y651299
X1878900Y637000
X1885300Y636800
X1851717Y635331
X1869500Y633500
X1859117Y620131
X1858917Y614481
X1859232Y508600
X1864232
X1890000Y440000
Y420000
Y400000
Y380000
Y360000
X1880000Y340000
Y320000
X1860000
X1881088Y296184
X1880969Y276861
X1865169Y247161
Y234661
X1850669Y219661
X1873500Y219000
X1898669Y217441
X1856219Y212661
X1898669Y207992
X1875669Y201661
X1870669
X1856219
X1880669
X1865669
X1898669Y198543
X1885204Y184345
X1876938Y181062
X1851717Y179075
X1869500Y179134
X1859117Y167375
X1859017Y161725
X1880000Y140000
X1860000
Y120000
X1880000
X1860000Y100000
X1880000
Y80000
X1860000
Y60000
X1880000
X1920000
X1900000
X1920000Y80000
X1900000
Y100000
X1920000
X1900000Y120000
X1920000
X1910169Y141870
X1903169Y165492
Y180492
Y195492
Y235492
Y245492
Y265492
Y275492
X1910169Y314114
Y594626
X1903169Y618248
Y633248
Y648248
Y688248
Y698248
Y718248
Y728248
X1910169Y766870
X1908107Y831894
X1902607
X1912551Y836444
Y841944
X1902499Y846368
X1907999
X1902441Y888500
X1906500Y893400
X1911676Y893469
X1909358Y897500
X1904000Y921000
Y925000
Y929000
Y933500
Y938000
X1910169Y1047382
X1903169Y1071004
Y1086004
Y1101004
Y1141004
X1903100Y1149700
X1903169Y1171004
Y1181004
X1910169Y1219626
X1900000Y1260000
X1920000
Y1280000
X1900000
X1920000Y1300000
X1900000
X1920000Y1320000
X1900000
T04
X436811Y124507
X450984
X465157
X479830
X521850
X536023
X550197
X564370
X1447834
X1490354
X1504527
X1518701
X1532874
X1137446Y995679
Y1009852
Y1024025
Y1038198
Y1167343
Y1181516
Y1195690
Y1209863
Y1224036
Y1238209
Y1252383
Y1266556
Y1280729
Y1294902
Y1309076
Y1323249
Y1337422
Y1351595
Y1365769
Y1379942
Y1394115
Y1408288
T05
X429724Y63977
Y68307
Y73819
Y78150
Y82481
Y87993
Y92323
Y96654
Y102166
Y106496
Y110827
Y116339
Y120670
X436811Y120276
Y114764
Y110433
Y106103
Y100591
Y96260
Y91930
Y86418
Y82087
Y77756
Y72245
Y67914
X443898Y63977
Y68307
Y73819
Y78150
Y82481
Y87993
Y92323
Y96654
Y102166
Y106496
Y110827
Y116339
Y120670
X458071
X450984Y120276
X458071Y116339
X450984Y114764
X458071Y110827
X450984Y110433
X458071Y106496
X450984Y106103
X458071Y102166
X450984Y100591
X458071Y96654
X450984Y96260
X458071Y92323
X450984Y91930
X458071Y87993
X450984Y86418
X458071Y82481
X450984Y82087
X458071Y78150
X450984Y77756
X458071Y73819
X450984Y72245
X458071Y68307
X450984Y67914
X458071Y63977
X465157Y67914
Y72245
Y77756
Y82087
Y86418
Y91930
Y96260
Y100591
Y106103
Y110433
Y114764
Y120276
X472244Y120670
X479331Y120276
X472244Y116339
X479331Y114764
X472244Y110827
X479331Y110433
X472244Y106496
X479331Y106103
X472244Y102166
X479331Y100591
X472244Y96654
X479331Y96260
X472244Y92323
X479331Y91930
X472244Y87993
X479331Y86418
X472244Y82481
X479331Y82087
X472244Y78150
X479331Y77756
X472244Y73819
X479331Y72245
X472244Y68307
X479331Y67914
X472244Y63977
X514764
Y68307
Y73819
Y78150
Y82481
Y87993
Y92323
Y96654
Y102166
Y106496
Y110827
Y116339
Y120670
X528937
X521850Y120276
X528937Y116339
X521850Y114764
X528937Y110827
X521850Y110433
X528937Y106496
X521850Y106103
X528937Y102166
X521850Y100591
X528937Y96654
X521850Y96260
X528937Y92323
X521850Y91930
X528937Y87993
X521850Y86418
X528937Y82481
X521850Y82087
X528937Y78150
X521850Y77756
X528937Y73819
X521850Y72245
X528937Y68307
X521850Y67914
X528937Y63977
X536024Y67914
Y72245
Y77756
Y82087
Y86418
Y91930
Y96260
Y100591
Y106103
Y110433
Y114764
Y120276
X543110Y120670
Y116339
Y110827
Y106496
Y102166
Y96654
Y92323
Y87993
Y82481
Y78150
Y73819
Y68307
Y63977
X557283
X550197Y67914
X557283Y68307
X550197Y72245
X557283Y73819
X550197Y77756
X557283Y78150
X550197Y82087
X557283Y82481
X550197Y86418
X557283Y87993
X550197Y91930
X557283Y92323
X550197Y96260
X557283Y96654
X550197Y100591
X557283Y102166
X550197Y106103
X557283Y106496
X550197Y110433
X557283Y110827
X550197Y114764
X557283Y116339
X550197Y120276
X557283Y120670
X564370Y120276
Y114764
Y110433
Y106103
Y100591
Y96260
Y91930
Y86418
Y82087
Y77756
Y72245
Y67914
X826772Y1598032
Y1602363
Y1607874
Y1612205
Y1616536
Y1622048
Y1626378
Y1630709
Y1636221
Y1640551
Y1644882
Y1650394
X833859Y1650788
Y1646457
Y1640945
Y1636614
Y1632284
Y1626772
Y1622441
Y1618111
Y1612599
Y1608268
Y1603937
Y1598425
Y1594095
X848032
X840945Y1598032
X848032Y1598425
X840945Y1602363
X848032Y1603937
X840945Y1607874
X848032Y1608268
X840945Y1612205
X848032Y1612599
X840945Y1616536
X848032Y1618111
X840945Y1622048
X848032Y1622441
X840945Y1626378
X848032Y1626772
X840945Y1630709
X848032Y1632284
X840945Y1636221
X848032Y1636614
X840945Y1640551
X848032Y1640945
X840945Y1644882
X848032Y1646457
X840945Y1650394
X848032Y1650788
X855118Y1650394
Y1644882
Y1640551
Y1636221
Y1630709
Y1626378
Y1622048
Y1616536
Y1612205
Y1607874
Y1602363
Y1598032
X862205Y1594095
X869292Y1598032
X862205Y1598425
X869292Y1602363
X862205Y1603937
X869292Y1607874
X862205Y1608268
X869292Y1612205
X862205Y1612599
X869292Y1616536
X862205Y1618111
X869292Y1622048
X862205Y1622441
X869292Y1626378
X862205Y1626772
X869292Y1630709
X862205Y1632284
X869292Y1636221
X862205Y1636614
X869292Y1640551
X862205Y1640945
X869292Y1644882
X862205Y1646457
X869292Y1650394
X862205Y1650788
X876378
Y1646457
Y1640945
Y1636614
Y1632284
Y1626772
Y1622441
Y1618111
Y1612599
Y1608268
Y1603937
Y1598425
Y1594095
X897638
X890552Y1598032
X897638Y1598425
X890552Y1602363
X897638Y1603937
X890552Y1607874
X897638Y1608268
X890552Y1612205
X897638Y1612599
X890552Y1616536
X897638Y1618111
X890552Y1622048
X897638Y1622441
X890552Y1626378
X897638Y1626772
X890552Y1630709
X897638Y1632284
X890552Y1636221
X897638Y1636614
X890552Y1640551
X897638Y1640945
X890552Y1644882
X897638Y1646457
X890552Y1650394
X897638Y1650788
X904725Y1650394
Y1644882
Y1640551
Y1636221
Y1630709
Y1626378
Y1622048
Y1616536
Y1612205
Y1607874
Y1602363
Y1598032
X911811Y1594095
Y1598425
Y1603937
Y1608268
Y1612599
Y1618111
Y1622441
Y1626772
Y1632284
Y1636614
Y1640945
Y1646457
Y1650788
X1099357Y1408288
X1095026
X1095420Y1401201
X1091089
X1099357Y1394115
X1095026
X1091089Y1387028
X1095420
X1099357Y1379942
X1095026
X1091089Y1372855
X1095420
X1095026Y1365768
X1099357
X1095420Y1358682
X1091089
X1099357Y1351595
X1095026
X1095420Y1344508
X1091089
X1099357Y1337422
X1095026
X1091089Y1330335
X1095420
X1095026Y1323249
X1099357
X1095420Y1316162
X1091089
X1095026Y1309075
X1099357
X1095420Y1301989
X1091089
X1099357Y1294902
X1095026
X1091089Y1287816
X1095420
X1095026Y1280729
X1099357
X1095420Y1273642
X1091089
X1099357Y1266556
X1095026
X1095420Y1259469
X1091089
X1095026Y1252382
X1099357
X1091089Y1245296
X1095420
X1095026Y1238209
X1099357
X1095420Y1231123
X1091089
X1099357Y1224036
X1095026
X1095420Y1216949
X1091089
X1095026Y1209863
X1099357
X1091089Y1202776
X1095420
X1099357Y1195690
X1095026
X1095420Y1188603
X1091089
X1099357Y1181516
X1095026
X1095420Y1174430
X1091089
X1099357Y1167343
X1095026
X1091089Y1160257
X1095420
X1099357Y1038198
X1095026
X1091089Y1031111
X1095420
X1099357Y1024025
X1095026
X1095420Y1016938
X1091089
X1099357Y1009852
X1095026
X1095420Y1002765
X1091089
X1099357Y995678
X1095026
X1095420Y988592
X1091089
X1109593
X1100932
X1105262
X1104869Y995678
X1109199
X1100932Y1002765
X1109593
X1105262
X1104869Y1009852
X1109199
X1109593Y1016938
X1100932
X1105262
X1109199Y1024025
X1104869
X1109593Y1031111
X1105262
X1100932
X1109199Y1038198
X1104869
X1105262Y1160257
X1100932
X1109593
X1104869Y1167343
X1109199
X1109593Y1174430
X1105262
X1100932
X1104869Y1181516
X1109199
X1105262Y1188603
X1109593
X1100932
X1109199Y1195690
X1104869
X1100932Y1202776
X1105262
X1109593
X1109199Y1209863
X1104869
X1105262Y1216949
X1109593
X1100932
X1104869Y1224036
X1109199
X1105262Y1231123
X1100932
X1109593
X1109199Y1238209
X1104869
X1109593Y1245296
X1105262
X1100932
X1109199Y1252382
X1104869
X1105262Y1259469
X1100932
X1109593
X1104869Y1266556
X1109199
X1105262Y1273642
X1109593
X1100932
X1109199Y1280729
X1104869
X1100932Y1287816
X1109593
X1105262
X1104869Y1294902
X1109199
X1105262Y1301989
X1109593
X1100932
X1104869Y1309075
X1109199
X1109593Y1316162
X1105262
X1100932
X1104869Y1323249
X1109199
X1109593Y1330335
X1100932
X1105262
X1109199Y1337422
X1104869
X1109593Y1344508
X1105262
X1100932
X1104869Y1351595
X1109199
X1105262Y1358682
X1100932
X1109593
X1109199Y1365768
X1104869
X1100932Y1372855
X1109593
X1105262
X1109199Y1379942
X1104869
X1109593Y1387028
X1100932
X1105262
X1104869Y1394115
X1109199
X1100932Y1401201
X1105262
X1109593
X1109199Y1408288
X1104869
X1119042
X1113530
X1119435Y1401201
X1115105
X1113530Y1394115
X1119042
X1115105Y1387028
X1119435
X1113530Y1379942
X1119042
X1119435Y1372855
X1115105
X1113530Y1365768
X1119042
X1119435Y1358682
X1115105
X1119042Y1351595
X1113530
X1119435Y1344508
X1115105
X1119042Y1337422
X1113530
X1119435Y1330335
X1115105
X1113530Y1323249
X1119042
X1119435Y1316162
X1115105
X1119042Y1309075
X1113530
X1119435Y1301989
X1115105
X1119042Y1294902
X1113530
X1115105Y1287816
X1119435
X1119042Y1280729
X1113530
X1119435Y1273642
X1115105
X1113530Y1266556
X1119042
X1115105Y1259469
X1119435
X1113530Y1252382
X1119042
X1119435Y1245296
X1115105
X1119042Y1238209
X1113530
X1115105Y1231123
X1119435
X1113530Y1224036
X1119042
X1115105Y1216949
X1119435
X1113530Y1209863
X1119042
X1115105Y1202776
X1119435
X1119042Y1195690
X1113530
X1115105Y1188603
X1119435
X1113530Y1181516
X1119042
X1115105Y1174430
X1119435
X1113530Y1167343
X1119042
X1119435Y1160257
X1115105
X1119042Y1038198
X1113530
X1115105Y1031111
X1119435
X1119042Y1024025
X1113530
X1115105Y1016938
X1119435
X1113530Y1009852
X1119042
X1119435Y1002765
X1115105
X1119042Y995678
X1113530
X1119435Y988592
X1115105
X1123766
X1129278
X1127703Y995678
X1123372
X1123766Y1002765
X1129278
X1127703Y1009852
X1123372
X1123766Y1016938
X1129278
X1123372Y1024025
X1127703
X1123766Y1031111
X1129278
X1123372Y1038198
X1127703
X1123766Y1160257
X1129278
X1123372Y1167343
X1127703
X1123766Y1174430
X1129278
X1127703Y1181516
X1123372
X1123766Y1188603
X1129278
X1127703Y1195690
X1123372
X1129278Y1202776
X1123766
X1127703Y1209863
X1123372
X1129278Y1216949
X1123766
X1123372Y1224036
X1127703
X1129278Y1231123
X1123766
X1127703Y1238209
X1123372
X1123766Y1245296
X1129278
X1123372Y1252382
X1127703
X1129278Y1259469
X1123766
X1127703Y1266556
X1123372
X1123766Y1273642
X1129278
X1127703Y1280729
X1123372
X1129278Y1287816
X1123766
X1123372Y1294902
X1127703
X1123766Y1301989
X1129278
X1127703Y1309075
X1123372
X1123766Y1316162
X1129278
X1123372Y1323249
X1127703
X1123766Y1330335
X1129278
X1123372Y1337422
X1127703
X1129278Y1344508
X1123766
X1123372Y1351595
X1127703
X1129278Y1358682
X1123766
X1127703Y1365768
X1123372
X1123766Y1372855
X1129278
X1127703Y1379942
X1123372
X1123766Y1387028
X1129278
X1123372Y1394115
X1127703
X1123766Y1401201
X1129278
X1123372Y1408288
X1127703
X1133215
X1133609Y1401201
X1133215Y1394115
X1133609Y1387028
X1133215Y1379942
X1133609Y1372855
X1133215Y1365768
X1133609Y1358682
X1133215Y1351595
X1133609Y1344508
X1133215Y1337422
X1133609Y1330335
X1133215Y1323249
X1133609Y1316162
X1133215Y1309075
X1133609Y1301989
X1133215Y1294902
X1133609Y1287816
X1133215Y1280729
X1133609Y1273642
X1133215Y1266556
X1133609Y1259469
X1133215Y1252382
X1133609Y1245296
X1133215Y1238209
X1133609Y1231123
X1133215Y1224036
X1133609Y1216949
X1133215Y1209863
X1133609Y1202776
X1133215Y1195690
X1133609Y1188603
X1133215Y1181516
X1133609Y1174430
X1133215Y1167343
X1133609Y1160257
X1133215Y1038198
X1133609Y1031111
X1133215Y1024025
X1133609Y1016938
X1133215Y1009852
X1133609Y1002765
X1133215Y995678
X1133609Y988592
X1398228Y120670
Y116339
Y110827
Y106496
Y102166
Y96654
Y92323
Y87993
Y82481
Y78150
Y73819
Y68307
Y63977
X1405315Y67914
Y72245
Y77756
Y82087
Y86418
Y91930
Y96260
Y100591
Y106103
Y110433
Y114764
Y120276
X1412402Y120670
X1419488Y120276
X1412402Y116339
X1419488Y114764
X1412402Y110827
X1419488Y110433
X1412402Y106496
X1419488Y106103
X1412402Y102166
X1419488Y100591
X1412402Y96654
X1419488Y96260
X1412402Y92323
X1419488Y91930
X1412402Y87993
X1419488Y86418
X1412402Y82481
X1419488Y82087
X1412402Y78150
X1419488Y77756
X1412402Y73819
X1419488Y72245
X1412402Y68307
X1419488Y67914
X1412402Y63977
X1426575
Y68307
Y73819
Y78150
Y82481
Y87993
Y92323
Y96654
Y102166
Y106496
Y110827
Y116339
Y120670
X1433661Y120276
Y114764
Y110433
Y106103
Y100591
Y96260
Y91930
Y86418
Y82087
Y77756
Y72245
Y67914
X1440748Y63977
X1447835Y67914
X1440748Y68307
X1447835Y72245
X1440748Y73819
X1447835Y77756
X1440748Y78150
X1447835Y82087
X1440748Y82481
X1447835Y86418
X1440748Y87993
X1447835Y91930
X1440748Y92323
X1447835Y96260
X1440748Y96654
X1447835Y100591
X1440748Y102166
X1447835Y106103
X1440748Y106496
X1447835Y110433
X1440748Y110827
X1447835Y114764
X1440748Y116339
X1447835Y120276
X1440748Y120670
X1483268
Y116339
Y110827
Y106496
Y102166
Y96654
Y92323
Y87993
Y82481
Y78150
Y73819
Y68307
Y63977
X1497441
X1490354Y67914
X1497441Y68307
X1490354Y72245
X1497441Y73819
X1490354Y77756
X1497441Y78150
X1490354Y82087
X1497441Y82481
X1490354Y86418
X1497441Y87993
X1490354Y91930
X1497441Y92323
X1490354Y96260
X1497441Y96654
X1490354Y100591
X1497441Y102166
X1490354Y106103
X1497441Y106496
X1490354Y110433
X1497441Y110827
X1490354Y114764
X1497441Y116339
X1490354Y120276
X1497441Y120670
X1504528Y120276
Y114764
Y110433
Y106103
Y100591
Y96260
Y91930
Y86418
Y82087
Y77756
Y72245
Y67914
X1511614Y63977
X1518701Y67914
X1511614Y68307
X1518701Y72245
X1511614Y73819
X1518701Y77756
X1511614Y78150
X1518701Y82087
X1511614Y82481
X1518701Y86418
X1511614Y87993
X1518701Y91930
X1511614Y92323
X1518701Y96260
X1511614Y96654
X1518701Y100591
X1511614Y102166
X1518701Y106103
X1511614Y106496
X1518701Y110433
X1511614Y110827
X1518701Y114764
X1511614Y116339
X1518701Y120276
X1511614Y120670
X1525787
Y116339
Y110827
Y106496
Y102166
Y96654
Y92323
Y87993
Y82481
Y78150
Y73819
Y68307
Y63977
X1532874Y67914
Y72245
Y77756
Y82087
Y86418
Y91930
Y96260
Y100591
Y106103
Y110433
Y114764
Y120276
T06
X29508Y5500
X34508
X44508
X89508
X84508
X79508
X39508
X24508
X74508
X69508
X64508
X59508
X54508
X49508
X5500Y41492
Y46492
Y51492
Y56492
Y61492
Y66492
Y71492
Y76492
Y81492
Y86492
Y91492
Y96492
Y101492
Y106492
Y111492
Y116492
Y121492
Y126492
Y131492
Y136492
Y141492
Y146492
Y151492
Y156492
Y161492
Y166492
Y171492
Y176492
Y181492
Y186492
Y191492
Y196492
Y201492
Y206492
Y211492
Y216492
Y221492
Y226492
Y231492
Y236492
Y241492
Y246492
Y251492
Y256492
Y261492
Y266492
Y271492
Y276492
Y281492
Y286492
Y291492
Y296492
Y301492
Y306492
Y311492
Y316492
Y321492
Y326492
Y331492
Y336492
Y341492
Y346492
Y351492
Y356492
Y361492
Y366492
Y371492
Y376492
Y381492
Y386492
Y391492
Y396492
Y401492
Y406492
Y411492
Y416492
Y421492
Y426492
Y431492
Y436492
Y441492
Y446492
Y451492
Y456492
Y496492
Y501492
Y506492
Y511492
Y516492
Y521492
Y526492
Y531492
Y536492
Y541492
Y546492
Y551492
Y556492
Y561492
Y566492
Y571492
Y576492
Y581492
Y586492
Y591492
Y596492
Y601492
Y606492
Y611492
Y616492
Y621492
Y626492
Y631492
Y636492
Y641492
Y646492
Y651492
Y656492
Y661492
Y666492
Y671492
Y676492
Y681492
Y686492
Y691492
Y696492
Y701492
Y706492
Y711492
Y716492
Y721492
Y726492
Y731492
Y736492
Y741492
Y746492
Y751492
Y756492
Y761492
Y766492
Y771492
Y776492
Y781492
Y786492
Y791492
Y796492
Y801492
Y806492
Y811492
Y816492
Y821492
Y826492
Y831492
Y836492
Y841492
Y846492
Y851492
Y856492
Y861492
Y866492
Y871492
Y876492
Y881492
Y886492
Y891492
Y896492
Y901492
Y906492
Y911492
Y916492
Y921492
Y926492
Y931492
Y936492
Y941492
Y946492
Y951492
Y956492
Y961492
Y966492
Y971492
Y976492
X83100Y980300
X78600
X5500Y981492
X83100Y984800
X78600
X5500Y986492
X78600Y989300
X83100
X5500Y991492
Y996492
Y1001492
Y1006492
Y1011492
Y1016492
Y1021492
Y1026492
Y1031492
Y1036492
Y1041492
Y1046492
Y1051492
Y1056492
Y1061492
Y1066492
Y1071492
Y1076492
Y1081492
Y1086492
Y1091492
Y1096492
Y1101492
Y1106492
Y1111492
Y1116492
Y1121492
Y1126492
Y1131492
Y1136492
Y1141492
Y1146492
Y1151492
Y1156492
Y1161492
Y1166492
Y1171492
Y1176492
Y1181492
Y1186492
Y1191492
Y1196492
Y1201492
Y1206492
Y1211492
Y1216492
Y1221492
Y1226492
Y1231492
Y1236492
Y1241492
Y1246492
Y1251492
Y1256492
Y1261492
Y1266492
Y1271492
Y1276492
Y1281492
Y1286492
Y1291492
Y1296492
Y1301492
Y1306492
Y1311492
Y1316492
Y1321492
Y1326492
Y1331492
Y1336492
Y1341492
Y1346492
Y1351492
Y1356492
Y1361492
X18983Y1368303
X13983
X28983
X88983
X23983
X83983
X78983
X43983
X73983
X68983
X63983
X58983
X53983
X48983
X33983
X38983
X8983
X167374Y1369303
X162374
X147374
X132374
X157374
X152374
X137374
X142374
X127374
X177374
X107374
X112374
X117374
X122374
X172374
X98983Y1368303
X93983
X142006Y978425
X141978Y958572
X119763Y555225
X124263
Y550725
X119763
Y546225
X124263
X149508Y5500
X139508
X134508
X129508
X124508
X119508
X114508
X154508
X159508
X164508
X94508
X169508
X179508
X174508
X109508
X99508
X144508
X104508
X244508
X234508
X214508
X229508
X204508
X224508
X259508
X264508
X254508
X199508
X194508
X189508
X184508
X249508
X269508
X219508
X209508
X239508
X265545Y556794
X250650Y556997
X265545Y561794
X250650Y561997
X269763Y564725
X209863Y566625
X269763Y569725
X265590Y572801
X250661Y572936
X265590Y577801
X250661Y577936
X199102Y969717
X183584Y969789
X199102Y974717
X183584Y974789
X221063Y976725
X203063
X225563
X207563
X212063
X216563
X207563Y981725
X203063
X225563
X212063
X221063
X216563
X183551Y984789
X199392Y985113
X183551Y989789
X199392Y990113
X222374Y1369303
X212374
X227374
X262374
X192374
X187374
X217374
X182374
X232374
X237374
X242374
X247374
X197374
X202374
X252374
X207374
X257374
X267374
X312374
X317374
X322374
X327374
X292374
X297374
X277374
X272374
X282374
X307374
X302374
X287374
X338983Y1368303
X348983
X333983
X358983
X353983
X343983
X287763Y569725
X292263
X274263
X283263
X278763
X292263Y564725
X283263
X287763
X278763
X274263
X304508Y5500
X349508
X299508
X354508
X319508
X359508
X324508
X344508
X329508
X339508
X284508
X334508
X309508
X274508
X294508
X314508
X289508
X279508
X389508
X394508
X364508
X384508
X374508
X379508
X369508
X395075Y13639
Y18639
Y23639
Y28639
Y33639
Y38639
Y43639
X396075Y50248
X396000Y55500
X399000Y62000
X383983Y1368303
X388983
X393983
X398983
X373983
X368983
X363983
X378983
X438983
X433983
X428983
X448983
X418983
X413983
X408983
X443983
X403983
X423983
X463983
X468983
X473983
X453983
X498983
X493983
X488983
X458983
X483983
X478983
X503983
X508983
X522374Y1369303
X527374
X537374
X517374
X532374
X597374
X607374
X547374
X552374
X567374
X582374
X602374
X627374
X622374
X617374
X542374
X587374
X592374
X562374
X577374
X612374
X572374
X557374
X629192Y605786
Y601586
Y597386
Y593186
X589000Y64000
X594000Y61500
X596000Y56500
X596051Y51090
X597051Y42699
Y37699
Y32699
Y27699
Y22699
Y17699
Y12699
Y7699
X604146Y5500
X609146
X619146
X629146
X614146
X624146
X679146
X689146
X694146
X639146
X644146
X634146
X649146
X684146
X654146
X704146
X709146
X699146
X659146
X714146
X719146
X664146
X674146
X669146
X661682Y582834
X656482
X666882
X672082
X675913Y586555
X703813Y592355
X675913Y592955
X633392Y593186
X637592
X641792
X703813Y596555
X633392Y597386
X637592
X641792
X675913Y598155
X695413Y600755
X699613
X703813
X637592Y601586
X641792
X633392
X675913Y603355
X703813Y604955
X695413
X699613
X637592Y605786
X641792
X633392
X691213Y609155
X703813
X699613
X695413
X669482Y609734
X656882
X665282
X661082
X699613Y613355
X691213
X703813
X695413
X665282Y613934
X656882
X661082
X669482
X704399Y618399
Y622599
Y626799
X702483Y945989
X692374Y1369303
X682374
X677374
X667374
X662374
X657374
X652374
X697374
X647374
X642374
X687374
X637374
X632374
X672374
X712374
X717374
X702374
X707374
X792902Y1652964
X797902
X792902Y1647964
Y1642964
Y1637964
Y1632964
Y1627964
Y1622964
Y1617964
Y1612964
Y1607964
Y1602964
Y1597964
Y1592964
Y1587964
Y1582964
Y1577964
Y1572964
Y1567964
Y1562964
Y1557964
Y1552964
Y1547964
Y1542964
Y1537964
Y1532964
Y1527964
Y1522964
Y1517964
Y1512964
Y1507964
Y1502964
Y1497964
Y1492964
Y1487964
Y1482964
Y1477964
Y1472964
X790500Y1466500
X786000Y1463500
X779547Y1463004
X766156Y1462004
X771156
X756287Y1459264
Y1454264
X757287Y1445873
Y1440873
Y1435873
Y1430873
Y1425873
Y1420873
Y1415873
Y1410873
Y1405873
Y1400873
Y1395873
Y1390873
Y1385873
Y1380873
X755500Y1374500
X752500Y1370500
X722374Y1369303
X747374
X742374
X737374
X732374
X727374
X721552Y951317
X725852Y951067
X729146Y5500
X734146
X769146
X744146
X749146
X759146
X754146
X724146
X739146
X779146
X774146
X764146
X795969Y-1374
X872642Y-20575
Y-25575
Y-30575
Y-35575
Y-40575
Y-45575
Y-50575
Y-55575
Y-60575
Y-65575
Y-70575
Y-75575
Y-80575
Y-85575
Y-90575
Y-95575
Y-100575
Y-105575
Y-110575
Y-115575
Y-120575
Y-125575
Y-130575
Y-135575
Y-140575
X885264Y-147256
X890264
X895264
X875264
X880264
X925264
X920264
X915264
X910264
X905264
X940264
X900264
X930264
X950264
X945264
X955264
X965264
X970264
X975264
X980264
X985264
X960264
X935264
X995264
X1005264
X1010264
X1015264
X1020264
X1030264
X1035264
X990264
X1040264
X1000264
X1045264
X1050264
X1075264
X1055264
X1060264
X1065264
X1070264
X1025264
X1078098Y1652768
X1073098
X1138098
X1143098
X1103098
X1108098
X1123098
X1118098
X1128098
X1113098
X1083098
X1088098
X1153098
X1093098
X1098098
X1133098
X1148098
X1168098
X1163098
X1158098
X1166673Y1477941
X1161000Y1474500
X1158500Y1468500
X1158673Y1462067
Y1457067
Y1452067
Y1447067
Y1442067
Y1437067
Y1432067
Y1427067
Y1422067
Y1417067
Y1412067
Y1407067
Y1402067
Y1397067
Y1392067
Y1387067
Y1382067
Y1377067
X1162000Y1371500
X1169783Y1369303
X1165264Y-147256
X1105264
X1100264
X1110264
X1115264
X1120264
X1125264
X1130264
X1135264
X1140264
X1090264
X1145264
X1095264
X1150264
X1155264
X1160264
X1080264
X1085264
X1170264
X1175602Y-142594
Y-137594
Y-132594
Y-127594
Y-122594
Y-117594
Y-112594
Y-107594
Y-102594
Y-97594
Y-92594
Y-87594
Y-82594
Y-77594
Y-72594
Y-67594
Y-62594
Y-57594
Y-52594
Y-47594
Y-42594
Y-37594
Y-32594
Y-27594
Y-22594
Y-17594
Y-12594
Y-7594
X1176500Y-500
X1180500Y4000
X1186382Y5500
X1196382
X1236382
X1191382
X1241382
X1251382
X1226382
X1256382
X1221382
X1216382
X1211382
X1201382
X1246382
X1206382
X1231382
X1234783Y1369303
X1204783
X1239783
X1244783
X1249783
X1229783
X1224783
X1259783
X1219783
X1214783
X1209783
X1199783
X1184783
X1189783
X1179783
X1174783
X1194783
X1254783
X1206673Y1477941
X1201673
X1191673
X1196673
X1186673
X1176673
X1171673
X1211673
X1181673
X1214972Y1482642
Y1487642
Y1492642
Y1497642
Y1502642
Y1507642
Y1512642
Y1517642
Y1522642
Y1527642
Y1532642
Y1537642
Y1542642
Y1547642
Y1552642
Y1557642
Y1562642
Y1567642
Y1572642
Y1577642
Y1582642
Y1587642
Y1592642
Y1597642
Y1602642
Y1607642
Y1612642
Y1617642
Y1622642
Y1627642
Y1632642
Y1637642
Y1642642
Y1647642
X1188098Y1652768
X1198098
X1173098
X1178098
X1203098
X1183098
X1208098
X1213098
X1193098
X1329783Y1369303
X1304783
X1309783
X1314783
X1324783
X1319783
X1274783
X1279783
X1284783
X1289783
X1294783
X1344783
X1339783
X1299783
X1334783
X1269783
X1264783
X1349783
X1326382Y5500
X1306382
X1286382
X1261382
X1266382
X1271382
X1276382
X1296382
X1291382
X1281382
X1321382
X1301382
X1316382
X1311382
X1331382
X1336382
X1341382
X1346382
X1356382
X1351382
X1363579Y9821
Y14821
Y19821
Y24821
Y29821
Y34821
Y39821
Y44821
Y51618
X1374000Y64500
X1373900Y530200
X1382300
X1378100
X1365500
X1386500
X1369700
Y534400
X1373900
X1386500
X1382300
X1378100
X1365500
Y538600
X1369700
X1396500Y549500
X1370200Y550500
X1366000
X1370200Y554700
X1366000
X1396500
X1366000Y558900
X1370200
X1396500Y559900
X1366000Y563100
X1370200
X1396500Y565100
X1381600Y568500
X1387300
X1393000
X1375900
X1373700Y582900
X1369500
X1434581Y586136
X1373700Y587100
X1369500
X1377900
X1382100
X1386300
X1434441Y590424
X1369500Y591300
X1373700
X1377900
X1369500Y595500
X1373700
X1377900
X1369500Y599700
X1373700
X1377900
X1394783Y1369303
X1389783
X1384783
X1379783
X1374783
X1369783
X1364783
X1399783
X1359783
X1354783
X1409783
X1424783
X1419783
X1429783
X1434783
X1439783
X1414783
X1404783
X1474783
X1469783
X1464783
X1459783
X1484783
X1454783
X1449783
X1479783
X1444783
X1489783
X1494783
X1499783
X1524783
X1519783
X1514783
X1509783
X1504783
X1529783
X1604783
X1544783
X1569783
X1559783
X1554783
X1619783
X1614783
X1609783
X1549783
X1564783
X1539783
X1534783
X1579783
X1584783
X1589783
X1594783
X1574783
X1599783
X1557000Y64500
X1561500Y62000
X1564000Y57500
X1564555Y52124
X1565555Y41517
Y36517
Y31517
Y26517
Y21517
Y16517
X1613030Y5500
X1603030
X1618030
X1583030
X1568030
X1573030
X1598030
X1593030
X1588030
X1578030
X1608030
X1673030
X1623030
X1628030
X1633030
X1638030
X1643030
X1668030
X1648030
X1658030
X1688030
X1663030
X1653030
X1708030
X1703030
X1678030
X1683030
X1698030
X1693030
X1692761Y995347
X1697261
Y999847
X1692761
X1697261Y1004347
X1692761
X1689783Y1369303
X1679783
X1674783
X1669783
X1664783
X1659783
X1654783
X1684783
X1649783
X1644783
X1639783
X1634783
X1629783
X1624783
X1694783
X1699783
X1704783
X1709783
X1754783
X1719783
X1759783
X1714783
X1724783
X1729783
X1734783
X1739783
X1744783
X1749783
X1764783
X1794783
X1799783
X1769783
X1774783
X1779783
X1784783
X1789783
X1783806Y989468
X1793030Y5500
X1788030
X1783030
X1778030
X1773030
X1768030
X1763030
X1758030
X1718030
X1748030
X1723030
X1798030
X1713030
X1743030
X1738030
X1753030
X1733030
X1728030
X1873030
X1868030
X1863030
X1858030
X1853030
X1848030
X1883030
X1878030
X1843030
X1888030
X1838030
X1833030
X1828030
X1823030
X1818030
X1813030
X1808030
X1803030
X1873099Y803650
X1878099
Y808150
X1873099
Y812650
X1878099
Y817150
X1873099
X1878099Y821650
X1873099
X1878099Y826150
X1873099
X1873012Y831377
X1882512
X1877512
X1865202Y831559
X1862652Y846508
X1878373Y846472
X1883373
X1867652Y846508
X1845763Y956040
X1850263
X1845870Y960239
X1850370
X1845763Y964540
X1850263
X1825741Y969210
X1840683Y969318
X1825741Y974210
X1840683Y974318
X1858363Y978125
X1844863
X1862863
X1853863
X1849363
X1867363
X1858363Y983125
X1862863
X1849363
X1844863
X1867363
X1853863
X1840578Y985885
X1825744Y986011
X1840578Y990885
X1825744Y991011
X1889783Y1369303
X1874783
X1834783
X1864783
X1804783
X1859783
X1879783
X1884783
X1809783
X1814783
X1819783
X1839783
X1844783
X1824783
X1829783
X1869783
X1854783
X1849783
X1914783
X1894783
X1899783
X1924783
X1919783
X1904783
X1909783
X1929343Y1363863
Y1358863
Y1353863
Y1348863
Y1343863
Y1338863
Y1333863
Y1328863
Y1323863
Y1318863
Y1313863
Y1308863
Y1303863
Y1298863
Y1293863
Y1288863
Y1283863
Y1278863
Y1273863
Y1268863
Y1263863
Y1258863
Y1253863
Y1248863
Y1243863
Y1238863
Y1233863
Y1228863
Y1223863
Y1218863
Y1213863
Y1208863
Y1203863
Y1198863
Y1193863
Y1188863
Y1183863
Y1178863
Y1173863
Y1168863
Y1163863
Y1158863
Y1153863
Y1148863
Y1143863
Y1138863
Y1133863
Y1128863
Y1123863
Y1118863
Y1113863
Y1108863
Y1103863
Y1098863
Y1093863
Y1088863
Y1083863
Y1078863
Y1073863
Y1068863
Y1063863
Y1058863
Y1053863
Y1048863
Y1043863
Y1038863
Y1033863
Y1028863
Y1023863
Y1018863
Y1013863
Y1008863
Y1003863
Y998863
Y993863
Y988863
Y983863
Y978863
Y973863
Y966525
Y961525
Y956525
Y951525
Y946525
Y941525
Y936525
Y931525
Y926525
Y921525
Y916525
Y911525
Y906525
Y901525
Y896525
Y891525
Y886525
Y881525
Y876525
Y871525
Y866525
Y861525
Y856525
Y851525
Y846525
Y841525
Y836525
Y831525
Y826525
Y821525
Y816525
Y811525
Y806525
Y801525
Y796525
Y791525
Y786525
Y781525
Y776525
Y771525
Y766525
Y761525
Y756525
Y751525
Y746525
Y741525
Y736525
Y731525
Y726525
Y721525
Y716525
Y711525
Y706525
Y701525
Y696525
Y691525
Y686525
Y681525
Y676525
Y671525
Y666525
Y661525
Y656525
Y651525
Y646525
Y641525
Y636525
Y631525
Y626525
Y621525
Y616525
Y611525
Y606525
Y601525
Y596525
Y591525
Y586525
Y581525
Y576525
Y571525
Y566525
Y561525
Y556525
Y551525
Y546525
Y541525
Y536525
Y531525
Y526525
Y521525
Y516525
Y511525
Y506525
Y501525
Y496525
Y491525
Y486525
Y481525
Y476525
Y471525
Y466525
Y461525
Y456525
Y451525
Y446525
Y441525
Y436525
Y431525
Y426525
Y421525
Y416525
Y411525
Y406525
Y401525
Y396525
Y391525
Y386525
Y381525
Y376525
Y371525
Y366525
Y361525
Y356525
Y351525
Y346525
Y341525
Y336525
Y331525
Y326525
Y321525
Y316525
Y311525
Y306525
Y301525
Y296525
Y291525
Y286525
Y281525
Y276525
Y271525
Y266525
Y261525
Y256525
Y251525
Y246525
Y241525
Y236525
Y231525
Y226525
Y221525
Y216525
Y211525
Y206525
Y201525
Y196525
Y191525
Y186525
Y181525
Y176525
Y171525
Y166525
Y161525
Y156525
Y151525
Y146525
Y141525
Y136525
Y131525
Y126525
Y121525
Y116525
Y111525
Y106525
Y101525
Y96525
Y91525
Y86525
Y81525
Y76525
Y71525
Y66525
Y61525
Y56525
Y51525
Y46525
Y41525
Y36525
Y31525
Y26525
Y21525
Y16525
Y11525
Y6525
X1909030Y5500
X1914030
X1919030
X1924030
T07
X996400Y1463157
Y1467657
Y1472157
Y1476657
X995783Y1489593
Y1495593
Y1501593
Y1507593
X1000500Y1511400
X1005690Y1511178
X1005400Y1476657
X1000900
X1009900
X1000900Y1472157
X1005400
X1009900
X1005400Y1467657
X1000900
X1009900
X1005400Y1463157
X1009900
X1000900
X1019600Y1511100
X1010190Y1511178
X1014690
X1014950Y1528919
X1014867Y1534326
X1020290Y1534392
X1026376Y1534326
X1020373Y1528985
X1026459Y1528919
X1027290Y1511078
X1023583Y1507593
Y1501593
Y1495593
Y1489593
X1026345Y1476746
Y1472246
Y1467746
Y1463246
X1030845
X1035345
X1039845
X1035345Y1467746
X1030845
X1039845
X1035345Y1472246
X1030845
X1039845
Y1476746
X1030845
X1035345
X1031790Y1511078
X1036578Y1511210
X1031882Y1528985
X1031799Y1534392
X1040500Y1529290
X1040583Y1523883
Y1517883
X1041810Y1511084
X1059810
X1055310
X1051383Y1507593
Y1501593
Y1495593
Y1489593
X1053700Y1476600
X1058200
X1053700Y1472100
X1058200
X1053700Y1467600
X1058200
Y1463100
X1053700
X1062700
X1067200
X1062700Y1467600
X1067200
Y1472100
X1062700
X1067200Y1476600
X1062700
X1064310Y1511084
X1068810
X1078683Y1522593
Y1516593
X1073310Y1511084
X1078683Y1507593
Y1501593
Y1495593
Y1489593
T08
X988795Y1571058
Y1576658
X994460Y1577240
X994305Y1571942
Y1566342
X1005658Y1565005
X1000058
X1005658Y1570605
X1000058
X1005658Y1575905
X1000058
X1011676Y1576375
X1017223Y1574963
X1011476Y1570775
X1017023Y1569363
X1011476Y1565175
X1017023Y1563763
X1014974Y1545659
Y1540059
X1026106Y1539995
X1020574Y1540059
X1026106Y1545595
X1020574Y1545659
X1022623Y1563763
X1028223
X1022623Y1569363
X1028223
X1028423Y1574963
X1022823
X1039358Y1576605
X1033917Y1574834
X1039358Y1571005
X1033717Y1569234
X1039358Y1565405
X1033717Y1563634
X1039758Y1559605
X1031706Y1545595
Y1539995
X1039958Y1542505
Y1548105
Y1553705
X1055618Y1543685
Y1549285
Y1554885
X1055418Y1560785
X1055768Y1566675
Y1572275
Y1577875
X1061558Y1572305
X1067158
Y1566705
X1061558
X1067158Y1561105
X1061558
X1072758Y1572305
X1078358
Y1566705
X1072758
Y1561105
X1078358
T09
X929331Y16536
Y24410
Y32284
Y40158
Y48032
Y63780
Y71654
Y79528
Y87402
Y95276
Y103150
Y111024
Y118898
Y126772
Y134646
Y142520
Y150394
Y158268
Y166142
Y174016
Y181890
Y189764
Y197638
Y205512
Y213386
Y221260
Y229134
Y237008
Y244882
Y252756
Y260630
Y268504
Y276378
Y284252
Y292126
Y300000
Y307874
Y315748
Y323622
Y331496
Y339371
Y395669
Y403543
Y411417
Y419291
Y427165
Y442913
Y450787
Y458661
Y466535
Y474409
Y482283
Y490157
Y498031
Y505905
Y513779
Y521653
Y529527
Y537401
Y545275
Y553149
Y561023
Y568897
Y576771
Y584645
Y592519
Y600393
Y608267
Y616141
Y624015
Y631889
Y639763
Y647637
Y655511
Y663385
Y671259
Y679133
Y687007
Y694881
Y702755
Y710629
Y718504
X937205Y714567
Y706692
Y698818
Y690944
Y683070
Y675196
Y667322
Y659448
Y651574
Y643700
Y635826
Y627952
Y620078
Y612204
Y604330
Y596456
Y588582
Y580708
Y572834
Y564960
Y557086
Y549212
Y541338
Y533464
Y525590
Y517716
Y509842
Y501968
Y494094
Y486220
Y478346
Y470472
Y462598
Y454724
Y446850
Y431102
Y423228
Y415354
Y407480
Y399606
Y391732
Y335434
Y327559
Y319685
Y311811
Y303937
Y296063
Y288189
Y280315
Y272441
Y264567
Y256693
Y248819
Y240945
Y233071
Y225197
Y217323
Y209449
Y201575
Y193701
Y185827
Y177953
Y170079
Y162205
Y154331
Y146457
Y138583
Y130709
Y122835
Y114961
Y107087
Y99213
Y91339
Y83465
Y75591
Y67717
Y51969
Y44095
Y36221
Y28347
Y20473
Y12599
X947047
Y20473
Y28347
Y36221
Y44095
Y51969
Y67717
Y75591
Y83465
Y91339
Y99213
Y107087
Y114961
Y122835
Y130709
Y138583
Y146457
Y154331
Y162205
Y170079
Y177953
Y185827
Y193701
Y201575
Y209449
Y217323
Y225197
Y233071
Y240945
Y248819
Y256693
Y264567
Y272441
Y280315
Y288189
Y296063
Y303937
Y311811
Y319685
Y327559
Y335434
Y391732
Y399606
Y407480
Y415354
Y423228
Y431102
Y446850
Y454724
Y462598
Y470472
Y478346
Y486220
Y494094
Y501968
Y509842
Y517716
Y525590
Y533464
Y541338
Y549212
Y557086
Y564960
Y572834
Y580708
Y588582
Y596456
Y604330
Y612204
Y620078
Y627952
Y635826
Y643700
Y651574
Y659448
Y667322
Y675196
Y683070
Y690944
Y698818
Y706692
Y714567
X954921Y718504
Y710629
Y702755
Y694881
Y687007
Y679133
Y671259
Y663385
Y655511
Y647637
Y639763
Y631889
Y624015
Y616141
Y608267
Y600393
Y592519
Y584645
Y576771
Y568897
Y561023
Y553149
Y545275
Y537401
Y529527
Y521653
Y513779
Y505905
Y498031
Y490157
Y482283
Y474409
Y466535
Y458661
Y450787
Y442913
Y427165
Y419291
Y411417
Y403543
Y395669
Y339371
Y331496
Y323622
Y315748
Y307874
Y300000
Y292126
Y284252
Y276378
Y268504
Y260630
Y252756
Y244882
Y237008
Y229134
Y221260
Y213386
Y205512
Y197638
Y189764
Y181890
Y174016
Y166142
Y158268
Y150394
Y142520
Y134646
Y126772
Y118898
Y111024
Y103150
Y95276
Y87402
Y79528
Y71654
Y63780
Y48032
Y40158
Y32284
Y24410
Y16536
X1097441
Y24410
Y32284
Y40158
Y48032
Y63780
Y71654
Y79528
Y87402
Y95276
Y103150
Y111024
Y118898
Y126772
Y134646
Y142520
Y150394
Y158268
Y166142
Y174016
Y181890
Y189764
Y197638
Y205512
Y213386
Y221260
Y229134
Y237008
Y244882
Y252756
Y260630
Y268504
Y276378
Y284252
Y292126
Y300000
Y307874
Y315748
Y323622
Y331496
Y339371
Y395669
Y403543
Y411417
Y419291
Y427165
Y442913
Y450787
Y458661
Y466535
Y474409
Y482283
Y490157
Y498031
Y505905
Y513779
Y521653
Y529527
Y537401
Y545275
Y553149
Y561023
Y568897
Y576771
Y584645
Y592519
Y600393
Y608267
Y616141
Y624015
Y631889
Y639763
Y647637
Y655511
Y663385
Y671259
Y679133
Y687007
Y694881
Y702755
Y710629
Y718504
X1105315Y714567
Y706692
Y698818
Y690944
Y683070
Y675196
Y667322
Y659448
Y651574
Y643700
Y635826
Y627952
Y620078
Y612204
Y604330
Y596456
Y588582
Y580708
Y572834
Y564960
Y557086
Y549212
Y541338
Y533464
Y525590
Y517716
Y509842
Y501968
Y494094
Y486220
Y478346
Y470472
Y462598
Y454724
Y446850
Y431102
Y423228
Y415354
Y407480
Y399606
Y391732
Y335434
Y327559
Y319685
Y311811
Y303937
Y296063
Y288189
Y280315
Y272441
Y264567
Y256693
Y248819
Y240945
Y233071
Y225197
Y217323
Y209449
Y201575
Y193701
Y185827
Y177953
Y170079
Y162205
Y154331
Y146457
Y138583
Y130709
Y122835
Y114961
Y107087
Y99213
Y91339
Y83465
Y75591
Y67717
Y51969
Y44095
Y36221
Y28347
Y20473
Y12599
X1115157
Y20473
Y28347
Y36221
Y44095
Y51969
Y67717
Y75591
Y83465
Y91339
Y99213
Y107087
Y114961
Y122835
Y130709
Y138583
Y146457
Y154331
Y162205
Y170079
Y177953
Y185827
Y193701
Y201575
Y209449
Y217323
Y225197
Y233071
Y240945
Y248819
Y256693
Y264567
Y272441
Y280315
Y288189
Y296063
Y303937
Y311811
Y319685
Y327559
Y335434
Y391732
Y399606
Y407480
Y415354
Y423228
Y431102
Y446850
Y454724
Y462598
Y470472
Y478346
Y486220
Y494094
Y501968
Y509842
Y517716
Y525590
Y533464
Y541338
Y549212
Y557086
Y564960
Y572834
Y580708
Y588582
Y596456
Y604330
Y612204
Y620078
Y627952
Y635826
Y643700
Y651574
Y659448
Y667322
Y675196
Y683070
Y690944
Y698818
Y706692
Y714567
X1123031Y718504
Y710629
Y702755
Y694881
Y687007
Y679133
Y671259
Y663385
Y655511
Y647637
Y639763
Y631889
Y624015
Y616141
Y608267
Y600393
Y592519
Y584645
Y576771
Y568897
Y561023
Y553149
Y545275
Y537401
Y529527
Y521653
Y513779
Y505905
Y498031
Y490157
Y482283
Y474409
Y466535
Y458661
Y450787
Y442913
Y427165
Y419291
Y411417
Y403543
Y395669
Y339371
Y331496
Y323622
Y315748
Y307874
Y300000
Y292126
Y284252
Y276378
Y268504
Y260630
Y252756
Y244882
Y237008
Y229134
Y221260
Y213386
Y205512
Y197638
Y189764
Y181890
Y174016
Y166142
Y158268
Y150394
Y142520
Y134646
Y126772
Y118898
Y111024
Y103150
Y95276
Y87402
Y79528
Y71654
Y63780
Y48032
Y40158
Y32284
Y24410
Y16536
T10
X974016Y1591220
Y1597126
Y1603031
Y1613858
Y1619764
Y1625669
Y1636496
Y1642401
Y1648307
X986614
Y1642401
Y1636496
Y1625669
Y1619764
Y1613858
Y1603031
Y1597126
Y1591220
X1002362
Y1597126
Y1603031
Y1613858
Y1619764
Y1625669
Y1636496
Y1642401
Y1648307
X1014961
Y1642401
Y1636496
Y1625669
Y1619764
Y1613858
Y1603031
Y1597126
Y1591220
X1030709
Y1597126
Y1603031
Y1613858
Y1619764
Y1625669
Y1636496
Y1642401
Y1648307
X1043307
Y1642401
Y1636496
Y1625669
Y1619764
Y1613858
Y1603031
Y1597126
Y1591220
X1101457Y1588583
X1108150
Y1601181
X1101457
X1119685
Y1588583
X1126378
Y1601181
T11
X975786Y564960
T12
X1104527Y1630792
T13
X173228Y1062992
X421653Y1141732
X670079Y1062992
X1343701
X1592126Y1141732
X1840551Y1062992
T14
X15157Y21653
X904921Y564960
X1894685Y21654
T15
X31496Y882677
X168307Y646457
X660236
X718110Y820866
X1366142Y646457
X1462992Y866929
X1602756Y646457
X1903346Y803937
T16
X103642Y36220
X654822
X1274311
X1825492
T17
X949902Y-115157
X111024Y153681
X235236
X359449
X483661
X607874
X732087
X1281693
X1405906
X1530118
X1654331
X1778543
X1902756
Y606437
X1778543
X1654331
X1530118
X1405906
X1281693
X732087
X607874
X483661
X359449
X235236
X111024
Y1059193
X235236
X359449
X483661
X607874
X732087
X1281693
X1405906
X1530118
X1654331
X1778543
X1902756
T18
X1098524Y-115157
X1902756Y302303
X1778543
X1654331
X1530118
X1405906
X1281693
X732087
X607874
X483661
X359449
X235236
X111024
Y755059
X235236
X359449
X483661
X607874
X732087
X1281693
X1405906
X1530118
X1654331
X1778543
X1902756
Y1207815
X1778543
X1654331
X1530118
X1405906
X1281693
X732087
X607874
X483661
X359449
X235236
X111024
T19
X59536Y1573374
X79000Y1301900
X60540Y-85109
X1826700Y77600
X1898432Y-93682
X1908500Y1346800
X1865705Y1573374
T20
X80019Y51968
X127263Y20472
X631200Y51968
X678444Y20472
X1250689Y51969
X1297933Y20472
X1801870Y51969
X1849114Y20472
T21
X942126Y58465
X1110236
Y346457
X942126
Y437598
X1110236
Y725590
X942126
T22
X496653Y80906
X1465157
T23
X496653Y110552
X1465157
T24
X173228Y1114173
X670079
X1343700
X1840551
T25
X503248Y829921
X1673917
M30
